(kicad_sch (version 20230121) (generator eeschema)

  (paper "A3")

  (title_block
    (title "D1600E PSU Breakout Board")
    (date "2023-10-18")
    (rev "1.4.3")
    (comment 1 "www.antmicro.com")
    (comment 2 "Antmicro Ltd.")
  )

  (junction (at 180.34 73.66) (diameter 0) (color 0 0 0 0)
  )
  (junction (at 81.28 83.82) (diameter 0) (color 0 0 0 0)
  )
  (junction (at 133.35 245.11) (diameter 0) (color 0 0 0 0)
  )
  (junction (at 308.61 31.75) (diameter 0) (color 0 0 0 0)
  )
  (junction (at 308.61 34.29) (diameter 0) (color 0 0 0 0)
  )
  (junction (at 86.36 238.76) (diameter 0) (color 0 0 0 0)
  )
  (junction (at 63.5 83.82) (diameter 0) (color 0 0 0 0)
  )
  (junction (at 88.9 62.23) (diameter 0) (color 0 0 0 0)
  )
  (junction (at 172.72 59.69) (diameter 0) (color 0 0 0 0)
  )
  (junction (at 53.34 55.88) (diameter 0) (color 0 0 0 0)
  )
  (junction (at 153.67 97.79) (diameter 0) (color 0 0 0 0)
  )
  (junction (at 53.34 128.27) (diameter 0) (color 0 0 0 0)
  )
  (junction (at 339.09 58.42) (diameter 0) (color 0 0 0 0)
  )
  (junction (at 295.91 151.13) (diameter 0) (color 0 0 0 0)
  )
  (junction (at 72.39 86.36) (diameter 0) (color 0 0 0 0)
  )
  (junction (at 311.15 68.58) (diameter 0) (color 0 0 0 0)
  )
  (junction (at 303.53 151.13) (diameter 0) (color 0 0 0 0)
  )
  (junction (at 97.79 80.01) (diameter 0) (color 0 0 0 0)
  )
  (junction (at 177.8 110.49) (diameter 0) (color 0 0 0 0)
  )
  (junction (at 129.54 229.87) (diameter 0) (color 0 0 0 0)
  )
  (junction (at 81.28 62.23) (diameter 0) (color 0 0 0 0)
  )
  (junction (at 101.6 55.88) (diameter 0) (color 0 0 0 0)
  )
  (junction (at 102.87 165.1) (diameter 0) (color 0 0 0 0)
  )
  (junction (at 133.35 229.87) (diameter 0) (color 0 0 0 0)
  )
  (junction (at 45.72 55.88) (diameter 0) (color 0 0 0 0)
  )
  (junction (at 308.61 36.83) (diameter 0) (color 0 0 0 0)
  )
  (junction (at 101.6 73.66) (diameter 0) (color 0 0 0 0)
  )
  (junction (at 73.66 128.27) (diameter 0) (color 0 0 0 0)
  )
  (junction (at 72.39 62.23) (diameter 0) (color 0 0 0 0)
  )
  (junction (at 97.79 62.23) (diameter 0) (color 0 0 0 0)
  )
  (junction (at 38.1 55.88) (diameter 0) (color 0 0 0 0)
  )
  (junction (at 313.69 58.42) (diameter 0) (color 0 0 0 0)
  )
  (junction (at 54.61 86.36) (diameter 0) (color 0 0 0 0)
  )
  (junction (at 335.28 151.13) (diameter 0) (color 0 0 0 0)
  )
  (junction (at 140.97 229.87) (diameter 0) (color 0 0 0 0)
  )
  (junction (at 172.72 76.2) (diameter 0) (color 0 0 0 0)
  )
  (junction (at 331.47 68.58) (diameter 0) (color 0 0 0 0)
  )
  (junction (at 172.72 78.74) (diameter 0) (color 0 0 0 0)
  )
  (junction (at 177.8 95.25) (diameter 0) (color 0 0 0 0)
  )
  (junction (at 334.01 71.12) (diameter 0) (color 0 0 0 0)
  )
  (junction (at 39.37 83.82) (diameter 0) (color 0 0 0 0)
  )
  (junction (at 140.97 242.57) (diameter 0) (color 0 0 0 0)
  )
  (junction (at 322.58 55.88) (diameter 0) (color 0 0 0 0)
  )
  (junction (at 186.69 95.25) (diameter 0) (color 0 0 0 0)
  )
  (junction (at 308.61 71.12) (diameter 0) (color 0 0 0 0)
  )

  (no_connect (at 144.78 105.41))
  (no_connect (at 144.78 107.95))
  (no_connect (at 144.78 110.49))
  (no_connect (at 144.78 113.03))
  (no_connect (at 144.78 116.84))
  (no_connect (at 144.78 119.38))
  (no_connect (at 144.78 121.92))
  (no_connect (at 144.78 124.46))
  (no_connect (at 144.78 127))
  (no_connect (at 144.78 129.54))
  (no_connect (at 144.78 132.08))
  (no_connect (at 144.78 134.62))
  (no_connect (at 144.78 138.43))
  (no_connect (at 144.78 140.97))
  (no_connect (at 144.78 143.51))
  (no_connect (at 144.78 146.05))
  (no_connect (at 144.78 148.59))
  (no_connect (at 144.78 151.13))
  (no_connect (at 144.78 153.67))
  (no_connect (at 144.78 156.21))
  (no_connect (at 144.78 100.33))
  (no_connect (at 144.78 102.87))
  (no_connect (at 144.78 83.82))
  (no_connect (at 144.78 86.36))
  (no_connect (at 144.78 88.9))
  (no_connect (at 144.78 91.44))
  (no_connect (at 144.78 95.25))
  (no_connect (at 104.14 123.19))
  (no_connect (at 104.14 120.65))
  (no_connect (at 104.14 118.11))
  (no_connect (at 144.78 161.29))
  (no_connect (at 144.78 163.83))

  (wire (pts (xy 339.09 60.96) (xy 339.09 58.42))
    (stroke (width 0) (type default))
  )
  (wire (pts (xy 72.39 62.23) (xy 72.39 64.77))
    (stroke (width 0) (type default))
  )
  (wire (pts (xy 306.07 66.04) (xy 308.61 66.04))
    (stroke (width 0) (type default))
  )
  (wire (pts (xy 63.5 133.35) (xy 63.5 148.59))
    (stroke (width 0) (type default))
  )
  (wire (pts (xy 354.33 207.01) (xy 350.52 207.01))
    (stroke (width 0) (type default))
  )
  (wire (pts (xy 172.72 76.2) (xy 172.72 78.74))
    (stroke (width 0) (type default))
  )
  (wire (pts (xy 303.53 151.13) (xy 303.53 153.67))
    (stroke (width 0) (type default))
  )
  (wire (pts (xy 54.61 86.36) (xy 54.61 90.17))
    (stroke (width 0) (type default))
  )
  (wire (pts (xy 177.8 106.68) (xy 177.8 110.49))
    (stroke (width 0) (type default))
  )
  (wire (pts (xy 101.6 52.07) (xy 101.6 55.88))
    (stroke (width 0) (type default))
  )
  (wire (pts (xy 144.78 78.74) (xy 172.72 78.74))
    (stroke (width 0) (type default))
  )
  (wire (pts (xy 127 242.57) (xy 140.97 242.57))
    (stroke (width 0) (type default))
  )
  (wire (pts (xy 297.18 31.75) (xy 308.61 31.75))
    (stroke (width 0) (type default))
  )
  (wire (pts (xy 88.9 62.23) (xy 81.28 62.23))
    (stroke (width 0) (type default))
  )
  (wire (pts (xy 350.52 203.2) (xy 354.33 203.2))
    (stroke (width 0) (type default))
  )
  (wire (pts (xy 63.5 62.23) (xy 63.5 64.77))
    (stroke (width 0) (type default))
  )
  (wire (pts (xy 196.85 255.27) (xy 196.85 254))
    (stroke (width 0) (type default))
  )
  (wire (pts (xy 72.39 95.25) (xy 72.39 97.79))
    (stroke (width 0) (type default))
  )
  (wire (pts (xy 295.91 151.13) (xy 295.91 153.67))
    (stroke (width 0) (type default))
  )
  (wire (pts (xy 326.39 151.13) (xy 335.28 151.13))
    (stroke (width 0) (type default))
  )
  (wire (pts (xy 306.07 78.74) (xy 307.34 78.74))
    (stroke (width 0) (type default))
  )
  (wire (pts (xy 81.28 83.82) (xy 81.28 90.17))
    (stroke (width 0) (type default))
  )
  (wire (pts (xy 81.28 62.23) (xy 81.28 64.77))
    (stroke (width 0) (type default))
  )
  (wire (pts (xy 153.67 229.87) (xy 153.67 243.84))
    (stroke (width 0) (type default))
  )
  (wire (pts (xy 153.67 121.92) (xy 153.67 123.19))
    (stroke (width 0) (type default))
  )
  (wire (pts (xy 127 245.11) (xy 133.35 245.11))
    (stroke (width 0) (type default))
  )
  (wire (pts (xy 166.37 76.2) (xy 172.72 76.2))
    (stroke (width 0) (type default))
  )
  (wire (pts (xy 38.1 55.88) (xy 30.48 55.88))
    (stroke (width 0) (type default))
  )
  (wire (pts (xy 133.35 238.76) (xy 133.35 245.11))
    (stroke (width 0) (type default))
  )
  (wire (pts (xy 308.61 93.98) (xy 308.61 92.71))
    (stroke (width 0) (type default))
  )
  (wire (pts (xy 153.67 114.3) (xy 153.67 116.84))
    (stroke (width 0) (type default))
  )
  (wire (pts (xy 172.72 78.74) (xy 184.15 78.74))
    (stroke (width 0) (type default))
  )
  (wire (pts (xy 276.86 219.71) (xy 276.86 224.79))
    (stroke (width 0) (type default))
  )
  (wire (pts (xy 53.34 119.38) (xy 53.34 128.27))
    (stroke (width 0) (type default))
  )
  (wire (pts (xy 172.72 59.69) (xy 180.34 59.69))
    (stroke (width 0) (type default))
  )
  (wire (pts (xy 177.8 95.25) (xy 177.8 101.6))
    (stroke (width 0) (type default))
  )
  (wire (pts (xy 306.07 68.58) (xy 311.15 68.58))
    (stroke (width 0) (type default))
  )
  (wire (pts (xy 140.97 229.87) (xy 133.35 229.87))
    (stroke (width 0) (type default))
  )
  (wire (pts (xy 308.61 26.67) (xy 308.61 31.75))
    (stroke (width 0) (type default))
  )
  (wire (pts (xy 144.78 97.79) (xy 153.67 97.79))
    (stroke (width 0) (type default))
  )
  (wire (pts (xy 186.69 114.3) (xy 186.69 123.19))
    (stroke (width 0) (type default))
  )
  (wire (pts (xy 180.34 68.58) (xy 180.34 73.66))
    (stroke (width 0) (type default))
  )
  (wire (pts (xy 95.25 151.13) (xy 95.25 157.48))
    (stroke (width 0) (type default))
  )
  (wire (pts (xy 88.9 69.85) (xy 88.9 72.39))
    (stroke (width 0) (type default))
  )
  (wire (pts (xy 83.82 110.49) (xy 87.63 110.49))
    (stroke (width 0) (type default))
  )
  (wire (pts (xy 38.1 63.5) (xy 38.1 66.04))
    (stroke (width 0) (type default))
  )
  (wire (pts (xy 102.87 165.1) (xy 102.87 167.64))
    (stroke (width 0) (type default))
  )
  (wire (pts (xy 92.71 99.06) (xy 104.14 99.06))
    (stroke (width 0) (type default))
  )
  (wire (pts (xy 354.33 210.82) (xy 350.52 210.82))
    (stroke (width 0) (type default))
  )
  (wire (pts (xy 308.61 71.12) (xy 306.07 71.12))
    (stroke (width 0) (type default))
  )
  (wire (pts (xy 140.97 242.57) (xy 143.51 242.57))
    (stroke (width 0) (type default))
  )
  (wire (pts (xy 133.35 245.11) (xy 143.51 245.11))
    (stroke (width 0) (type default))
  )
  (wire (pts (xy 316.23 36.83) (xy 308.61 36.83))
    (stroke (width 0) (type default))
  )
  (wire (pts (xy 205.74 95.25) (xy 212.09 95.25))
    (stroke (width 0) (type default))
  )
  (wire (pts (xy 205.74 226.06) (xy 209.55 226.06))
    (stroke (width 0) (type default))
  )
  (wire (pts (xy 170.18 114.3) (xy 172.72 114.3))
    (stroke (width 0) (type default))
  )
  (wire (pts (xy 316.23 34.29) (xy 308.61 34.29))
    (stroke (width 0) (type default))
  )
  (wire (pts (xy 41.91 86.36) (xy 39.37 86.36))
    (stroke (width 0) (type default))
  )
  (wire (pts (xy 101.6 76.2) (xy 104.14 76.2))
    (stroke (width 0) (type default))
  )
  (wire (pts (xy 63.5 95.25) (xy 63.5 97.79))
    (stroke (width 0) (type default))
  )
  (wire (pts (xy 72.39 69.85) (xy 72.39 72.39))
    (stroke (width 0) (type default))
  )
  (wire (pts (xy 187.96 106.68) (xy 186.69 106.68))
    (stroke (width 0) (type default))
  )
  (wire (pts (xy 331.47 93.98) (xy 331.47 87.63))
    (stroke (width 0) (type default))
  )
  (wire (pts (xy 36.83 83.82) (xy 39.37 83.82))
    (stroke (width 0) (type default))
  )
  (wire (pts (xy 187.96 114.3) (xy 186.69 114.3))
    (stroke (width 0) (type default))
  )
  (wire (pts (xy 375.92 36.83) (xy 383.54 36.83))
    (stroke (width 0) (type default))
  )
  (wire (pts (xy 331.47 68.58) (xy 331.47 85.09))
    (stroke (width 0) (type default))
  )
  (wire (pts (xy 308.61 87.63) (xy 308.61 86.36))
    (stroke (width 0) (type default))
  )
  (wire (pts (xy 350.52 222.25) (xy 354.33 222.25))
    (stroke (width 0) (type default))
  )
  (wire (pts (xy 53.34 128.27) (xy 59.69 128.27))
    (stroke (width 0) (type default))
  )
  (wire (pts (xy 53.34 83.82) (xy 63.5 83.82))
    (stroke (width 0) (type default))
  )
  (wire (pts (xy 153.67 97.79) (xy 156.21 97.79))
    (stroke (width 0) (type default))
  )
  (wire (pts (xy 153.67 110.49) (xy 157.48 110.49))
    (stroke (width 0) (type default))
  )
  (wire (pts (xy 129.54 238.76) (xy 127 238.76))
    (stroke (width 0) (type default))
  )
  (wire (pts (xy 209.55 110.49) (xy 205.74 110.49))
    (stroke (width 0) (type default))
  )
  (wire (pts (xy 73.66 128.27) (xy 73.66 137.16))
    (stroke (width 0) (type default))
  )
  (wire (pts (xy 307.34 76.2) (xy 306.07 76.2))
    (stroke (width 0) (type default))
  )
  (wire (pts (xy 339.09 58.42) (xy 339.09 55.88))
    (stroke (width 0) (type default))
  )
  (wire (pts (xy 48.26 83.82) (xy 39.37 83.82))
    (stroke (width 0) (type default))
  )
  (wire (pts (xy 308.61 36.83) (xy 308.61 50.8))
    (stroke (width 0) (type default))
  )
  (wire (pts (xy 104.14 248.92) (xy 106.68 248.92))
    (stroke (width 0) (type default))
  )
  (wire (pts (xy 39.37 86.36) (xy 39.37 83.82))
    (stroke (width 0) (type default))
  )
  (wire (pts (xy 180.34 59.69) (xy 180.34 63.5))
    (stroke (width 0) (type default))
  )
  (wire (pts (xy 54.61 86.36) (xy 72.39 86.36))
    (stroke (width 0) (type default))
  )
  (wire (pts (xy 186.69 106.68) (xy 186.69 95.25))
    (stroke (width 0) (type default))
  )
  (wire (pts (xy 102.87 245.11) (xy 106.68 245.11))
    (stroke (width 0) (type default))
  )
  (wire (pts (xy 288.29 151.13) (xy 295.91 151.13))
    (stroke (width 0) (type default))
  )
  (wire (pts (xy 313.69 54.61) (xy 313.69 58.42))
    (stroke (width 0) (type default))
  )
  (wire (pts (xy 72.39 86.36) (xy 104.14 86.36))
    (stroke (width 0) (type default))
  )
  (wire (pts (xy 172.72 68.58) (xy 172.72 76.2))
    (stroke (width 0) (type default))
  )
  (wire (pts (xy 306.07 86.36) (xy 308.61 86.36))
    (stroke (width 0) (type default))
  )
  (wire (pts (xy 30.48 63.5) (xy 30.48 66.04))
    (stroke (width 0) (type default))
  )
  (wire (pts (xy 104.14 254) (xy 104.14 248.92))
    (stroke (width 0) (type default))
  )
  (wire (pts (xy 331.47 87.63) (xy 335.28 87.63))
    (stroke (width 0) (type default))
  )
  (wire (pts (xy 104.14 165.1) (xy 102.87 165.1))
    (stroke (width 0) (type default))
  )
  (wire (pts (xy 92.71 96.52) (xy 104.14 96.52))
    (stroke (width 0) (type default))
  )
  (wire (pts (xy 81.28 83.82) (xy 104.14 83.82))
    (stroke (width 0) (type default))
  )
  (wire (pts (xy 163.83 97.79) (xy 161.29 97.79))
    (stroke (width 0) (type default))
  )
  (polyline (pts (xy 227.33 104.14) (xy 407.67 104.14))
    (stroke (width 0) (type dash))
  )

  (wire (pts (xy 335.28 158.75) (xy 335.28 161.29))
    (stroke (width 0) (type default))
  )
  (wire (pts (xy 30.48 55.88) (xy 30.48 58.42))
    (stroke (width 0) (type default))
  )
  (wire (pts (xy 53.34 55.88) (xy 45.72 55.88))
    (stroke (width 0) (type default))
  )
  (wire (pts (xy 54.61 95.25) (xy 54.61 97.79))
    (stroke (width 0) (type default))
  )
  (wire (pts (xy 172.72 59.69) (xy 172.72 63.5))
    (stroke (width 0) (type default))
  )
  (wire (pts (xy 102.87 162.56) (xy 102.87 165.1))
    (stroke (width 0) (type default))
  )
  (wire (pts (xy 63.5 83.82) (xy 63.5 90.17))
    (stroke (width 0) (type default))
  )
  (wire (pts (xy 153.67 229.87) (xy 140.97 229.87))
    (stroke (width 0) (type default))
  )
  (wire (pts (xy 45.72 63.5) (xy 45.72 66.04))
    (stroke (width 0) (type default))
  )
  (wire (pts (xy 172.72 114.3) (xy 172.72 123.19))
    (stroke (width 0) (type default))
  )
  (wire (pts (xy 322.58 83.82) (xy 306.07 83.82))
    (stroke (width 0) (type default))
  )
  (wire (pts (xy 326.39 58.42) (xy 339.09 58.42))
    (stroke (width 0) (type default))
  )
  (wire (pts (xy 308.61 31.75) (xy 308.61 34.29))
    (stroke (width 0) (type default))
  )
  (wire (pts (xy 85.09 133.35) (xy 85.09 119.38))
    (stroke (width 0) (type default))
  )
  (wire (pts (xy 336.55 55.88) (xy 339.09 55.88))
    (stroke (width 0) (type default))
  )
  (wire (pts (xy 81.28 62.23) (xy 72.39 62.23))
    (stroke (width 0) (type default))
  )
  (wire (pts (xy 335.28 151.13) (xy 344.17 151.13))
    (stroke (width 0) (type default))
  )
  (wire (pts (xy 306.07 50.8) (xy 308.61 50.8))
    (stroke (width 0) (type default))
  )
  (wire (pts (xy 86.36 226.06) (xy 86.36 238.76))
    (stroke (width 0) (type default))
  )
  (wire (pts (xy 363.22 36.83) (xy 370.84 36.83))
    (stroke (width 0) (type default))
  )
  (wire (pts (xy 350.52 218.44) (xy 354.33 218.44))
    (stroke (width 0) (type default))
  )
  (wire (pts (xy 177.8 90.17) (xy 177.8 95.25))
    (stroke (width 0) (type default))
  )
  (wire (pts (xy 331.47 85.09) (xy 335.28 85.09))
    (stroke (width 0) (type default))
  )
  (wire (pts (xy 45.72 55.88) (xy 38.1 55.88))
    (stroke (width 0) (type default))
  )
  (wire (pts (xy 153.67 97.79) (xy 153.67 110.49))
    (stroke (width 0) (type default))
  )
  (wire (pts (xy 335.28 151.13) (xy 335.28 153.67))
    (stroke (width 0) (type default))
  )
  (wire (pts (xy 334.01 71.12) (xy 350.52 71.12))
    (stroke (width 0) (type default))
  )
  (wire (pts (xy 196.85 240.03) (xy 200.66 240.03))
    (stroke (width 0) (type default))
  )
  (wire (pts (xy 101.6 55.88) (xy 101.6 73.66))
    (stroke (width 0) (type default))
  )
  (wire (pts (xy 308.61 34.29) (xy 308.61 36.83))
    (stroke (width 0) (type default))
  )
  (wire (pts (xy 97.79 58.42) (xy 97.79 62.23))
    (stroke (width 0) (type default))
  )
  (wire (pts (xy 140.97 238.76) (xy 140.97 242.57))
    (stroke (width 0) (type default))
  )
  (wire (pts (xy 308.61 66.04) (xy 308.61 71.12))
    (stroke (width 0) (type default))
  )
  (wire (pts (xy 88.9 62.23) (xy 88.9 64.77))
    (stroke (width 0) (type default))
  )
  (wire (pts (xy 311.15 63.5) (xy 306.07 63.5))
    (stroke (width 0) (type default))
  )
  (wire (pts (xy 274.32 199.39) (xy 276.86 199.39))
    (stroke (width 0) (type default))
  )
  (wire (pts (xy 295.91 151.13) (xy 303.53 151.13))
    (stroke (width 0) (type default))
  )
  (wire (pts (xy 334.01 71.12) (xy 334.01 82.55))
    (stroke (width 0) (type default))
  )
  (wire (pts (xy 95.25 162.56) (xy 95.25 167.64))
    (stroke (width 0) (type default))
  )
  (wire (pts (xy 322.58 55.88) (xy 331.47 55.88))
    (stroke (width 0) (type default))
  )
  (wire (pts (xy 170.18 110.49) (xy 177.8 110.49))
    (stroke (width 0) (type default))
  )
  (wire (pts (xy 313.69 39.37) (xy 316.23 39.37))
    (stroke (width 0) (type default))
  )
  (wire (pts (xy 322.58 54.61) (xy 322.58 55.88))
    (stroke (width 0) (type default))
  )
  (wire (pts (xy 97.79 80.01) (xy 97.79 88.9))
    (stroke (width 0) (type default))
  )
  (wire (pts (xy 73.66 142.24) (xy 73.66 148.59))
    (stroke (width 0) (type default))
  )
  (wire (pts (xy 102.87 242.57) (xy 106.68 242.57))
    (stroke (width 0) (type default))
  )
  (wire (pts (xy 53.34 55.88) (xy 53.34 58.42))
    (stroke (width 0) (type default))
  )
  (wire (pts (xy 331.47 68.58) (xy 350.52 68.58))
    (stroke (width 0) (type default))
  )
  (wire (pts (xy 205.74 240.03) (xy 210.82 240.03))
    (stroke (width 0) (type default))
  )
  (wire (pts (xy 354.33 226.06) (xy 350.52 226.06))
    (stroke (width 0) (type default))
  )
  (wire (pts (xy 63.5 83.82) (xy 81.28 83.82))
    (stroke (width 0) (type default))
  )
  (wire (pts (xy 129.54 229.87) (xy 133.35 229.87))
    (stroke (width 0) (type default))
  )
  (wire (pts (xy 276.86 210.82) (xy 276.86 214.63))
    (stroke (width 0) (type default))
  )
  (wire (pts (xy 129.54 248.92) (xy 129.54 254))
    (stroke (width 0) (type default))
  )
  (polyline (pts (xy 227.33 13.97) (xy 227.33 284.48))
    (stroke (width 0) (type dash))
  )

  (wire (pts (xy 153.67 248.92) (xy 153.67 254))
    (stroke (width 0) (type default))
  )
  (wire (pts (xy 177.8 95.25) (xy 186.69 95.25))
    (stroke (width 0) (type default))
  )
  (wire (pts (xy 101.6 73.66) (xy 104.14 73.66))
    (stroke (width 0) (type default))
  )
  (wire (pts (xy 53.34 55.88) (xy 101.6 55.88))
    (stroke (width 0) (type default))
  )
  (wire (pts (xy 97.79 62.23) (xy 97.79 80.01))
    (stroke (width 0) (type default))
  )
  (wire (pts (xy 73.66 128.27) (xy 104.14 128.27))
    (stroke (width 0) (type default))
  )
  (wire (pts (xy 144.78 73.66) (xy 180.34 73.66))
    (stroke (width 0) (type default))
  )
  (wire (pts (xy 210.82 254) (xy 210.82 255.27))
    (stroke (width 0) (type default))
  )
  (wire (pts (xy 45.72 55.88) (xy 45.72 58.42))
    (stroke (width 0) (type default))
  )
  (wire (pts (xy 196.85 254) (xy 200.66 254))
    (stroke (width 0) (type default))
  )
  (wire (pts (xy 88.9 62.23) (xy 97.79 62.23))
    (stroke (width 0) (type default))
  )
  (wire (pts (xy 313.69 41.91) (xy 313.69 39.37))
    (stroke (width 0) (type default))
  )
  (wire (pts (xy 328.93 161.29) (xy 328.93 153.67))
    (stroke (width 0) (type default))
  )
  (wire (pts (xy 81.28 95.25) (xy 81.28 97.79))
    (stroke (width 0) (type default))
  )
  (wire (pts (xy 177.8 110.49) (xy 187.96 110.49))
    (stroke (width 0) (type default))
  )
  (wire (pts (xy 306.07 58.42) (xy 313.69 58.42))
    (stroke (width 0) (type default))
  )
  (wire (pts (xy 86.36 238.76) (xy 86.36 242.57))
    (stroke (width 0) (type default))
  )
  (wire (pts (xy 53.34 142.24) (xy 53.34 148.59))
    (stroke (width 0) (type default))
  )
  (wire (pts (xy 53.34 63.5) (xy 53.34 66.04))
    (stroke (width 0) (type default))
  )
  (wire (pts (xy 127 248.92) (xy 129.54 248.92))
    (stroke (width 0) (type default))
  )
  (wire (pts (xy 311.15 68.58) (xy 331.47 68.58))
    (stroke (width 0) (type default))
  )
  (wire (pts (xy 144.78 76.2) (xy 161.29 76.2))
    (stroke (width 0) (type default))
  )
  (wire (pts (xy 63.5 69.85) (xy 63.5 72.39))
    (stroke (width 0) (type default))
  )
  (wire (pts (xy 198.12 226.06) (xy 200.66 226.06))
    (stroke (width 0) (type default))
  )
  (wire (pts (xy 129.54 229.87) (xy 129.54 238.76))
    (stroke (width 0) (type default))
  )
  (wire (pts (xy 92.71 110.49) (xy 104.14 110.49))
    (stroke (width 0) (type default))
  )
  (wire (pts (xy 38.1 55.88) (xy 38.1 58.42))
    (stroke (width 0) (type default))
  )
  (wire (pts (xy 311.15 63.5) (xy 311.15 68.58))
    (stroke (width 0) (type default))
  )
  (wire (pts (xy 46.99 86.36) (xy 54.61 86.36))
    (stroke (width 0) (type default))
  )
  (wire (pts (xy 53.34 128.27) (xy 53.34 137.16))
    (stroke (width 0) (type default))
  )
  (polyline (pts (xy 12.065 199.39) (xy 227.33 199.39))
    (stroke (width 0) (type dash))
  )

  (wire (pts (xy 205.74 254) (xy 210.82 254))
    (stroke (width 0) (type default))
  )
  (wire (pts (xy 295.91 158.75) (xy 295.91 161.29))
    (stroke (width 0) (type default))
  )
  (wire (pts (xy 133.35 229.87) (xy 133.35 233.68))
    (stroke (width 0) (type default))
  )
  (wire (pts (xy 306.07 55.88) (xy 322.58 55.88))
    (stroke (width 0) (type default))
  )
  (wire (pts (xy 350.52 214.63) (xy 354.33 214.63))
    (stroke (width 0) (type default))
  )
  (wire (pts (xy 276.86 199.39) (xy 276.86 205.74))
    (stroke (width 0) (type default))
  )
  (wire (pts (xy 168.91 59.69) (xy 172.72 59.69))
    (stroke (width 0) (type default))
  )
  (wire (pts (xy 303.53 151.13) (xy 306.07 151.13))
    (stroke (width 0) (type default))
  )
  (wire (pts (xy 289.56 31.75) (xy 289.56 34.29))
    (stroke (width 0) (type default))
  )
  (wire (pts (xy 186.69 95.25) (xy 200.66 95.25))
    (stroke (width 0) (type default))
  )
  (wire (pts (xy 104.14 162.56) (xy 102.87 162.56))
    (stroke (width 0) (type default))
  )
  (wire (pts (xy 72.39 62.23) (xy 63.5 62.23))
    (stroke (width 0) (type default))
  )
  (wire (pts (xy 81.28 69.85) (xy 81.28 72.39))
    (stroke (width 0) (type default))
  )
  (wire (pts (xy 97.79 80.01) (xy 104.14 80.01))
    (stroke (width 0) (type default))
  )
  (wire (pts (xy 212.09 95.25) (xy 212.09 99.06))
    (stroke (width 0) (type default))
  )
  (wire (pts (xy 322.58 83.82) (xy 322.58 93.98))
    (stroke (width 0) (type default))
  )
  (wire (pts (xy 85.09 133.35) (xy 104.14 133.35))
    (stroke (width 0) (type default))
  )
  (wire (pts (xy 153.67 114.3) (xy 157.48 114.3))
    (stroke (width 0) (type default))
  )
  (wire (pts (xy 308.61 71.12) (xy 334.01 71.12))
    (stroke (width 0) (type default))
  )
  (wire (pts (xy 85.09 119.38) (xy 53.34 119.38))
    (stroke (width 0) (type default))
  )
  (wire (pts (xy 101.6 76.2) (xy 101.6 73.66))
    (stroke (width 0) (type default))
  )
  (wire (pts (xy 292.1 31.75) (xy 289.56 31.75))
    (stroke (width 0) (type default))
  )
  (wire (pts (xy 86.36 247.65) (xy 86.36 254))
    (stroke (width 0) (type default))
  )
  (wire (pts (xy 144.78 81.28) (xy 151.13 81.28))
    (stroke (width 0) (type default))
  )
  (wire (pts (xy 303.53 153.67) (xy 306.07 153.67))
    (stroke (width 0) (type default))
  )
  (wire (pts (xy 72.39 86.36) (xy 72.39 90.17))
    (stroke (width 0) (type default))
  )
  (wire (pts (xy 97.79 88.9) (xy 104.14 88.9))
    (stroke (width 0) (type default))
  )
  (wire (pts (xy 140.97 229.87) (xy 140.97 233.68))
    (stroke (width 0) (type default))
  )
  (wire (pts (xy 313.69 58.42) (xy 321.31 58.42))
    (stroke (width 0) (type default))
  )
  (wire (pts (xy 129.54 226.06) (xy 129.54 229.87))
    (stroke (width 0) (type default))
  )
  (wire (pts (xy 334.01 82.55) (xy 335.28 82.55))
    (stroke (width 0) (type default))
  )
  (wire (pts (xy 95.25 151.13) (xy 104.14 151.13))
    (stroke (width 0) (type default))
  )
  (wire (pts (xy 86.36 238.76) (xy 106.68 238.76))
    (stroke (width 0) (type default))
  )
  (wire (pts (xy 326.39 153.67) (xy 328.93 153.67))
    (stroke (width 0) (type default))
  )
  (wire (pts (xy 180.34 73.66) (xy 184.15 73.66))
    (stroke (width 0) (type default))
  )
  (wire (pts (xy 67.31 128.27) (xy 73.66 128.27))
    (stroke (width 0) (type default))
  )

  (text "FTDI" (at 123.19 19.05 0)
    (effects (font (size 2.9972 2.9972)) (justify left bottom))
  )
  (text "USB Connector\n" (at 304.8 19.05 0)
    (effects (font (size 2.9972 2.9972)) (justify left bottom))
  )
  (text "I2C separation & protection" (at 81.28 209.55 0)
    (effects (font (size 2.9972 2.9972)) (justify left bottom))
  )
  (text "Probes" (at 346.71 198.12 0)
    (effects (font (size 2.9972 2.9972)) (justify left bottom))
  )
  (text "Power LED" (at 264.16 193.04 0)
    (effects (font (size 2.9972 2.9972)) (justify left bottom))
  )
  (text "3V3 LDO\n" (at 307.34 135.89 0)
    (effects (font (size 2.9972 2.9972)) (justify left bottom))
  )

  (label "WP" (at 147.32 81.28 0) (fields_autoplaced)
    (effects (font (size 1.27 1.27)) (justify left bottom))
  )
  (label "USB_D+" (at 92.71 96.52 0) (fields_autoplaced)
    (effects (font (size 1.4986 1.4986)) (justify left bottom))
  )
  (label "OSCO" (at 96.52 133.35 0) (fields_autoplaced)
    (effects (font (size 1.27 1.27)) (justify left bottom))
  )
  (label "USB_D-" (at 92.71 99.06 0) (fields_autoplaced)
    (effects (font (size 1.4986 1.4986)) (justify left bottom))
  )
  (label "FTDI_VPLL" (at 92.71 86.36 180) (fields_autoplaced)
    (effects (font (size 1.27 1.27)) (justify right bottom))
  )
  (label "USB_D+" (at 350.52 68.58 180) (fields_autoplaced)
    (effects (font (size 1.4986 1.4986)) (justify right bottom))
  )
  (label "OSCI" (at 96.52 128.27 0) (fields_autoplaced)
    (effects (font (size 1.27 1.27)) (justify left bottom))
  )
  (label "SDA_FTDI_2" (at 146.05 76.2 0) (fields_autoplaced)
    (effects (font (size 1.27 1.27)) (justify left bottom))
  )
  (label "FTDI_VPHY" (at 92.71 83.82 180) (fields_autoplaced)
    (effects (font (size 1.27 1.27)) (justify right bottom))
  )
  (label "FTDI_RST" (at 95.25 110.49 0) (fields_autoplaced)
    (effects (font (size 1.27 1.27)) (justify left bottom))
  )
  (label "USB_D-" (at 350.52 71.12 180) (fields_autoplaced)
    (effects (font (size 1.4986 1.4986)) (justify right bottom))
  )

  (global_label "VBUS" (shape input) (at 308.61 26.67 180) (fields_autoplaced)
    (effects (font (size 1.4986 1.4986)) (justify right))
    (property "Intersheetrefs" "${INTERSHEET_REFS}" (at 300.0794 26.67 0)
      (effects (font (size 1.27 1.27)) (justify right) hide)
    )
  )
  (global_label "SDA_FTDI" (shape bidirectional) (at 198.12 226.06 180) (fields_autoplaced)
    (effects (font (size 1.27 1.27)) (justify right))
    (property "Intersheetrefs" "${INTERSHEET_REFS}" (at 24.765 -33.655 0)
      (effects (font (size 1.27 1.27)) hide)
    )
  )
  (global_label "SCL_FTDI" (shape bidirectional) (at 102.87 245.11 180) (fields_autoplaced)
    (effects (font (size 1.27 1.27)) (justify right))
    (property "Intersheetrefs" "${INTERSHEET_REFS}" (at 49.53 9.525 0)
      (effects (font (size 1.27 1.27)) hide)
    )
  )
  (global_label "SCL" (shape bidirectional) (at 210.82 240.03 0) (fields_autoplaced)
    (effects (font (size 1.27 1.27)) (justify left))
    (property "Intersheetrefs" "${INTERSHEET_REFS}" (at 27.305 -22.225 0)
      (effects (font (size 1.27 1.27)) hide)
    )
  )
  (global_label "VCC3V3" (shape input) (at 129.54 226.06 180) (fields_autoplaced)
    (effects (font (size 1.27 1.27)) (justify right))
    (property "Intersheetrefs" "${INTERSHEET_REFS}" (at 42.545 8.255 0)
      (effects (font (size 1.27 1.27)) hide)
    )
  )
  (global_label "VCC3V3_USB" (shape input) (at 83.82 110.49 180) (fields_autoplaced)
    (effects (font (size 1.27 1.27)) (justify right))
    (property "Intersheetrefs" "${INTERSHEET_REFS}" (at 69.5752 110.49 0)
      (effects (font (size 1.27 1.27)) (justify right) hide)
    )
  )
  (global_label "VCC5V0_USB" (shape input) (at 288.29 151.13 180) (fields_autoplaced)
    (effects (font (size 1.4986 1.4986)) (justify right))
    (property "Intersheetrefs" "${INTERSHEET_REFS}" (at -7.62 20.32 0)
      (effects (font (size 1.27 1.27)) hide)
    )
  )
  (global_label "VBUS" (shape input) (at 363.22 36.83 180) (fields_autoplaced)
    (effects (font (size 1.4986 1.4986)) (justify right))
    (property "Intersheetrefs" "${INTERSHEET_REFS}" (at 26.67 -5.08 0)
      (effects (font (size 1.27 1.27)) hide)
    )
  )
  (global_label "VCC3V3_USB" (shape input) (at 36.83 83.82 180) (fields_autoplaced)
    (effects (font (size 1.27 1.27)) (justify right))
    (property "Intersheetrefs" "${INTERSHEET_REFS}" (at 22.5852 83.82 0)
      (effects (font (size 1.27 1.27)) (justify right) hide)
    )
  )
  (global_label "VCC3V3_USB" (shape input) (at 168.91 59.69 180) (fields_autoplaced)
    (effects (font (size 1.27 1.27)) (justify right))
    (property "Intersheetrefs" "${INTERSHEET_REFS}" (at 114.935 -158.115 0)
      (effects (font (size 1.27 1.27)) hide)
    )
  )
  (global_label "VCC3V3" (shape input) (at 177.8 90.17 180) (fields_autoplaced)
    (effects (font (size 1.27 1.27)) (justify right))
    (property "Intersheetrefs" "${INTERSHEET_REFS}" (at 168.3328 90.17 0)
      (effects (font (size 1.27 1.27)) (justify right) hide)
    )
  )
  (global_label "VCC3V3_USB" (shape input) (at 350.52 203.2 180) (fields_autoplaced)
    (effects (font (size 1.4986 1.4986)) (justify right))
    (property "Intersheetrefs" "${INTERSHEET_REFS}" (at 333.7115 203.2 0)
      (effects (font (size 1.27 1.27)) (justify right) hide)
    )
  )
  (global_label "SDA" (shape bidirectional) (at 143.51 242.57 0) (fields_autoplaced)
    (effects (font (size 1.27 1.27)) (justify left))
    (property "Intersheetrefs" "${INTERSHEET_REFS}" (at 39.37 9.525 0)
      (effects (font (size 1.27 1.27)) hide)
    )
  )
  (global_label "SCL" (shape input) (at 350.52 214.63 180) (fields_autoplaced)
    (effects (font (size 1.4986 1.4986)) (justify right))
    (property "Intersheetrefs" "${INTERSHEET_REFS}" (at 343.6307 214.63 0)
      (effects (font (size 1.27 1.27)) (justify right) hide)
    )
  )
  (global_label "VCC3V3_USB" (shape input) (at 86.36 226.06 180) (fields_autoplaced)
    (effects (font (size 1.27 1.27)) (justify right))
    (property "Intersheetrefs" "${INTERSHEET_REFS}" (at 32.385 8.255 0)
      (effects (font (size 1.27 1.27)) hide)
    )
  )
  (global_label "SCL" (shape bidirectional) (at 143.51 245.11 0) (fields_autoplaced)
    (effects (font (size 1.27 1.27)) (justify left))
    (property "Intersheetrefs" "${INTERSHEET_REFS}" (at 39.37 9.525 0)
      (effects (font (size 1.27 1.27)) hide)
    )
  )
  (global_label "VCC3V3" (shape input) (at 350.52 207.01 180) (fields_autoplaced)
    (effects (font (size 1.4986 1.4986)) (justify right))
    (property "Intersheetrefs" "${INTERSHEET_REFS}" (at 339.3491 207.01 0)
      (effects (font (size 1.27 1.27)) (justify right) hide)
    )
  )
  (global_label "VCC5V0_USB" (shape input) (at 350.52 210.82 180) (fields_autoplaced)
    (effects (font (size 1.4986 1.4986)) (justify right))
    (property "Intersheetrefs" "${INTERSHEET_REFS}" (at 333.7115 210.82 0)
      (effects (font (size 1.27 1.27)) (justify right) hide)
    )
  )
  (global_label "SCL_FTDI" (shape input) (at 350.52 222.25 180) (fields_autoplaced)
    (effects (font (size 1.4986 1.4986)) (justify right))
    (property "Intersheetrefs" "${INTERSHEET_REFS}" (at 337.8504 222.25 0)
      (effects (font (size 1.27 1.27)) (justify right) hide)
    )
  )
  (global_label "SDA" (shape bidirectional) (at 209.55 226.06 0) (fields_autoplaced)
    (effects (font (size 1.27 1.27)) (justify left))
    (property "Intersheetrefs" "${INTERSHEET_REFS}" (at 216.4016 226.06 0)
      (effects (font (size 1.27 1.27)) (justify left) hide)
    )
  )
  (global_label "SDA_FTDI" (shape bidirectional) (at 102.87 242.57 180) (fields_autoplaced)
    (effects (font (size 1.27 1.27)) (justify right))
    (property "Intersheetrefs" "${INTERSHEET_REFS}" (at 49.53 9.525 0)
      (effects (font (size 1.27 1.27)) hide)
    )
  )
  (global_label "SDA_FTDI" (shape input) (at 350.52 226.06 180) (fields_autoplaced)
    (effects (font (size 1.4986 1.4986)) (justify right))
    (property "Intersheetrefs" "${INTERSHEET_REFS}" (at 337.7791 226.06 0)
      (effects (font (size 1.27 1.27)) (justify right) hide)
    )
  )
  (global_label "VCC3V3_USB" (shape output) (at 344.17 151.13 0) (fields_autoplaced)
    (effects (font (size 1.4986 1.4986)) (justify left))
    (property "Intersheetrefs" "${INTERSHEET_REFS}" (at -5.08 20.32 0)
      (effects (font (size 1.27 1.27)) hide)
    )
  )
  (global_label "VCC3V3_USB" (shape input) (at 274.32 199.39 180) (fields_autoplaced)
    (effects (font (size 1.4986 1.4986)) (justify right))
    (property "Intersheetrefs" "${INTERSHEET_REFS}" (at 257.5115 199.39 0)
      (effects (font (size 1.27 1.27)) (justify right) hide)
    )
  )
  (global_label "SCL_FTDI" (shape output) (at 184.15 73.66 0) (fields_autoplaced)
    (effects (font (size 1.27 1.27)) (justify left))
    (property "Intersheetrefs" "${INTERSHEET_REFS}" (at 15.24 -31.75 0)
      (effects (font (size 1.27 1.27)) hide)
    )
  )
  (global_label "LED_DATA" (shape output) (at 163.83 97.79 0) (fields_autoplaced)
    (effects (font (size 1.27 1.27)) (justify left))
    (property "Intersheetrefs" "${INTERSHEET_REFS}" (at 174.9905 97.79 0)
      (effects (font (size 1.27 1.27)) (justify left) hide)
    )
  )
  (global_label "SDA_FTDI" (shape bidirectional) (at 184.15 78.74 0) (fields_autoplaced)
    (effects (font (size 1.27 1.27)) (justify left))
    (property "Intersheetrefs" "${INTERSHEET_REFS}" (at 15.24 -31.75 0)
      (effects (font (size 1.27 1.27)) hide)
    )
  )
  (global_label "SCL_FTDI" (shape bidirectional) (at 196.85 240.03 180) (fields_autoplaced)
    (effects (font (size 1.27 1.27)) (justify right))
    (property "Intersheetrefs" "${INTERSHEET_REFS}" (at 23.495 -22.225 0)
      (effects (font (size 1.27 1.27)) hide)
    )
  )
  (global_label "LED_DATA" (shape output) (at 209.55 110.49 0) (fields_autoplaced)
    (effects (font (size 1.27 1.27)) (justify left))
    (property "Intersheetrefs" "${INTERSHEET_REFS}" (at 220.7037 110.4106 0)
      (effects (font (size 1.27 1.27)) (justify left) hide)
    )
  )
  (global_label "VCC5V0_USB" (shape input) (at 383.54 36.83 0) (fields_autoplaced)
    (effects (font (size 1.4986 1.4986)) (justify left))
    (property "Intersheetrefs" "${INTERSHEET_REFS}" (at 26.67 -5.08 0)
      (effects (font (size 1.27 1.27)) hide)
    )
  )
  (global_label "SDA" (shape input) (at 350.52 218.44 180) (fields_autoplaced)
    (effects (font (size 1.4986 1.4986)) (justify right))
    (property "Intersheetrefs" "${INTERSHEET_REFS}" (at 343.5594 218.44 0)
      (effects (font (size 1.27 1.27)) (justify right) hide)
    )
  )
  (global_label "VCC3V3_USB" (shape input) (at 101.6 52.07 180) (fields_autoplaced)
    (effects (font (size 1.27 1.27)) (justify right))
    (property "Intersheetrefs" "${INTERSHEET_REFS}" (at 87.3552 52.07 0)
      (effects (font (size 1.27 1.27)) (justify right) hide)
    )
  )
  (global_label "1V8_FT" (shape input) (at 97.79 58.42 180) (fields_autoplaced)
    (effects (font (size 1.27 1.27)) (justify right))
    (property "Intersheetrefs" "${INTERSHEET_REFS}" (at 88.9276 58.42 0)
      (effects (font (size 1.27 1.27)) (justify right) hide)
    )
  )

  (symbol (lib_id "antmicroResonators:Resonator_12MHz_KX-7") (at 59.69 128.27 0) (unit 1)
    (in_bom yes) (on_board yes) (dnp no)
    (property "Reference" "Y1" (at 63.5 121.92 0)
      (effects (font (size 1.27 1.27)))
    )
    (property "Value" "Resonator_12MHz_KX_7" (at 74.93 140.97 0)
      (effects (font (size 1.27 1.27) (thickness 0.15)) (justify left bottom) hide)
    )
    (property "Footprint" "antmicro-footprints:Resonator_SMD_Geyer_KX-7_3.2x2.5x0.8mm" (at 74.93 143.51 0)
      (effects (font (size 1.27 1.27) (thickness 0.15)) (justify left bottom) hide)
    )
    (property "Datasheet" "https://media.distrelec.com/Web/Downloads/86/62/KX-7-12-88662.pdf" (at 74.93 146.05 0)
      (effects (font (size 1.27 1.27) (thickness 0.15)) (justify left bottom) hide)
    )
    (property "MPN" "KX-7_SMD_CRYSTAL_12,0 MHZ" (at 74.93 135.89 0)
      (effects (font (size 1.27 1.27) (thickness 0.15)) (justify left bottom) hide)
    )
    (property "Manufacturer" "Geyer Electronic" (at 74.93 148.59 0)
      (effects (font (size 1.27 1.27) (thickness 0.15)) (justify left bottom) hide)
    )
    (property "Author" "Antmicro" (at 74.93 151.13 0)
      (effects (font (size 1.27 1.27) (thickness 0.15)) (justify left bottom) hide)
    )
    (property "License" "Apache-2.0" (at 74.93 153.67 0)
      (effects (font (size 1.27 1.27) (thickness 0.15)) (justify left bottom) hide)
    )
    (property "Val" "12 MHz" (at 63.5 124.46 0)
      (effects (font (size 1.27 1.27) (thickness 0.15)))
    )
    (pin "1")
    (pin "2")
    (pin "3")
    (pin "4")
    (instances
      (project "d1600e-psu-breakout-board"
        (path ""
          (reference "Y1") (unit 1)
        )
      )
    )
  )

  (symbol (lib_name "C_100n_0402_4") (lib_id "antmicroCapacitors0402:C_100n_0402") (at 30.48 63.5 90) (unit 1)
    (in_bom yes) (on_board yes) (dnp no)
    (property "Reference" "C3" (at 31.115 59.055 90)
      (effects (font (size 1.27 1.27)) (justify right))
    )
    (property "Value" "C_100n_0402" (at 40.64 43.18 0)
      (effects (font (size 1.27 1.27) (thickness 0.15)) (justify left bottom) hide)
    )
    (property "Footprint" "antmicro-footprints:C_0402_1005Metric" (at 43.18 43.18 0)
      (effects (font (size 1.27 1.27) (thickness 0.15)) (justify left bottom) hide)
    )
    (property "Datasheet" "https://www.murata.com/products/productdetail?partno=GRM155R61H104KE14%23" (at 45.72 43.18 0)
      (effects (font (size 1.27 1.27) (thickness 0.15)) (justify left bottom) hide)
    )
    (property "Manufacturer" "Murata" (at 50.8 43.18 0)
      (effects (font (size 1.27 1.27) (thickness 0.15)) (justify left bottom) hide)
    )
    (property "MPN" "GRM155R61H104KE14D" (at 48.26 43.18 0)
      (effects (font (size 1.27 1.27) (thickness 0.15)) (justify left bottom) hide)
    )
    (property "Val" "100n" (at 31.115 62.865 90)
      (effects (font (size 1.27 1.27) (thickness 0.15)) (justify right))
    )
    (property "License" "Apache-2.0" (at 53.34 43.18 0)
      (effects (font (size 1.27 1.27) (thickness 0.15)) (justify left bottom) hide)
    )
    (property "Author" "Antmicro" (at 55.88 43.18 0)
      (effects (font (size 1.27 1.27) (thickness 0.15)) (justify left bottom) hide)
    )
    (property "Voltage" "50V" (at 58.42 43.18 0)
      (effects (font (size 1.27 1.27)) (justify left bottom) hide)
    )
    (property "Dielectric" "X5R" (at 60.96 43.18 0)
      (effects (font (size 1.27 1.27)) (justify left bottom) hide)
    )
    (pin "1")
    (pin "2")
    (instances
      (project "d1600e-psu-breakout-board"
        (path ""
          (reference "C3") (unit 1)
        )
      )
    )
  )

  (symbol (lib_name "C_100n_0402_6") (lib_id "antmicroCapacitors0402:C_100n_0402") (at 38.1 63.5 90) (unit 1)
    (in_bom yes) (on_board yes) (dnp no)
    (property "Reference" "C4" (at 38.735 59.055 90)
      (effects (font (size 1.27 1.27)) (justify right))
    )
    (property "Value" "C_100n_0402" (at 48.26 43.18 0)
      (effects (font (size 1.27 1.27) (thickness 0.15)) (justify left bottom) hide)
    )
    (property "Footprint" "antmicro-footprints:C_0402_1005Metric" (at 50.8 43.18 0)
      (effects (font (size 1.27 1.27) (thickness 0.15)) (justify left bottom) hide)
    )
    (property "Datasheet" "https://www.murata.com/products/productdetail?partno=GRM155R61H104KE14%23" (at 53.34 43.18 0)
      (effects (font (size 1.27 1.27) (thickness 0.15)) (justify left bottom) hide)
    )
    (property "Manufacturer" "Murata" (at 58.42 43.18 0)
      (effects (font (size 1.27 1.27) (thickness 0.15)) (justify left bottom) hide)
    )
    (property "MPN" "GRM155R61H104KE14D" (at 55.88 43.18 0)
      (effects (font (size 1.27 1.27) (thickness 0.15)) (justify left bottom) hide)
    )
    (property "Val" "100n" (at 38.735 62.865 90)
      (effects (font (size 1.27 1.27) (thickness 0.15)) (justify right))
    )
    (property "License" "Apache-2.0" (at 60.96 43.18 0)
      (effects (font (size 1.27 1.27) (thickness 0.15)) (justify left bottom) hide)
    )
    (property "Author" "Antmicro" (at 63.5 43.18 0)
      (effects (font (size 1.27 1.27) (thickness 0.15)) (justify left bottom) hide)
    )
    (property "Voltage" "50V" (at 66.04 43.18 0)
      (effects (font (size 1.27 1.27)) (justify left bottom) hide)
    )
    (property "Dielectric" "X5R" (at 68.58 43.18 0)
      (effects (font (size 1.27 1.27)) (justify left bottom) hide)
    )
    (pin "1")
    (pin "2")
    (instances
      (project "d1600e-psu-breakout-board"
        (path ""
          (reference "C4") (unit 1)
        )
      )
    )
  )

  (symbol (lib_name "C_100n_0402_7") (lib_id "antmicroCapacitors0402:C_100n_0402") (at 45.72 63.5 90) (unit 1)
    (in_bom yes) (on_board yes) (dnp no)
    (property "Reference" "C6" (at 46.355 59.055 90)
      (effects (font (size 1.27 1.27)) (justify right))
    )
    (property "Value" "C_100n_0402" (at 55.88 43.18 0)
      (effects (font (size 1.27 1.27) (thickness 0.15)) (justify left bottom) hide)
    )
    (property "Footprint" "antmicro-footprints:C_0402_1005Metric" (at 58.42 43.18 0)
      (effects (font (size 1.27 1.27) (thickness 0.15)) (justify left bottom) hide)
    )
    (property "Datasheet" "https://www.murata.com/products/productdetail?partno=GRM155R61H104KE14%23" (at 60.96 43.18 0)
      (effects (font (size 1.27 1.27) (thickness 0.15)) (justify left bottom) hide)
    )
    (property "Manufacturer" "Murata" (at 66.04 43.18 0)
      (effects (font (size 1.27 1.27) (thickness 0.15)) (justify left bottom) hide)
    )
    (property "MPN" "GRM155R61H104KE14D" (at 63.5 43.18 0)
      (effects (font (size 1.27 1.27) (thickness 0.15)) (justify left bottom) hide)
    )
    (property "Val" "100n" (at 46.355 62.865 90)
      (effects (font (size 1.27 1.27) (thickness 0.15)) (justify right))
    )
    (property "License" "Apache-2.0" (at 68.58 43.18 0)
      (effects (font (size 1.27 1.27) (thickness 0.15)) (justify left bottom) hide)
    )
    (property "Author" "Antmicro" (at 71.12 43.18 0)
      (effects (font (size 1.27 1.27) (thickness 0.15)) (justify left bottom) hide)
    )
    (property "Voltage" "50V" (at 73.66 43.18 0)
      (effects (font (size 1.27 1.27)) (justify left bottom) hide)
    )
    (property "Dielectric" "X5R" (at 76.2 43.18 0)
      (effects (font (size 1.27 1.27)) (justify left bottom) hide)
    )
    (pin "1")
    (pin "2")
    (instances
      (project "d1600e-psu-breakout-board"
        (path ""
          (reference "C6") (unit 1)
        )
      )
    )
  )

  (symbol (lib_name "C_100n_0402_8") (lib_id "antmicroCapacitors0402:C_100n_0402") (at 53.34 63.5 90) (unit 1)
    (in_bom yes) (on_board yes) (dnp no)
    (property "Reference" "C7" (at 53.975 59.055 90)
      (effects (font (size 1.27 1.27)) (justify right))
    )
    (property "Value" "C_100n_0402" (at 63.5 43.18 0)
      (effects (font (size 1.27 1.27) (thickness 0.15)) (justify left bottom) hide)
    )
    (property "Footprint" "antmicro-footprints:C_0402_1005Metric" (at 66.04 43.18 0)
      (effects (font (size 1.27 1.27) (thickness 0.15)) (justify left bottom) hide)
    )
    (property "Datasheet" "https://www.murata.com/products/productdetail?partno=GRM155R61H104KE14%23" (at 68.58 43.18 0)
      (effects (font (size 1.27 1.27) (thickness 0.15)) (justify left bottom) hide)
    )
    (property "Manufacturer" "Murata" (at 73.66 43.18 0)
      (effects (font (size 1.27 1.27) (thickness 0.15)) (justify left bottom) hide)
    )
    (property "MPN" "GRM155R61H104KE14D" (at 71.12 43.18 0)
      (effects (font (size 1.27 1.27) (thickness 0.15)) (justify left bottom) hide)
    )
    (property "Val" "100n" (at 53.975 62.865 90)
      (effects (font (size 1.27 1.27) (thickness 0.15)) (justify right))
    )
    (property "License" "Apache-2.0" (at 76.2 43.18 0)
      (effects (font (size 1.27 1.27) (thickness 0.15)) (justify left bottom) hide)
    )
    (property "Author" "Antmicro" (at 78.74 43.18 0)
      (effects (font (size 1.27 1.27) (thickness 0.15)) (justify left bottom) hide)
    )
    (property "Voltage" "50V" (at 81.28 43.18 0)
      (effects (font (size 1.27 1.27)) (justify left bottom) hide)
    )
    (property "Dielectric" "X5R" (at 83.82 43.18 0)
      (effects (font (size 1.27 1.27)) (justify left bottom) hide)
    )
    (pin "1")
    (pin "2")
    (instances
      (project "d1600e-psu-breakout-board"
        (path ""
          (reference "C7") (unit 1)
        )
      )
    )
  )

  (symbol (lib_name "C_100n_0402_5") (lib_id "antmicroCapacitors0402:C_100n_0402") (at 81.28 69.85 270) (mirror x) (unit 1)
    (in_bom yes) (on_board yes) (dnp no)
    (property "Reference" "C9" (at 84.455 65.405 90)
      (effects (font (size 1.27 1.27)) (justify right))
    )
    (property "Value" "C_100n_0402" (at 71.12 49.53 0)
      (effects (font (size 1.27 1.27) (thickness 0.15)) (justify left bottom) hide)
    )
    (property "Footprint" "antmicro-footprints:C_0402_1005Metric" (at 68.58 49.53 0)
      (effects (font (size 1.27 1.27) (thickness 0.15)) (justify left bottom) hide)
    )
    (property "Datasheet" "https://www.murata.com/products/productdetail?partno=GRM155R61H104KE14%23" (at 66.04 49.53 0)
      (effects (font (size 1.27 1.27) (thickness 0.15)) (justify left bottom) hide)
    )
    (property "Manufacturer" "Murata" (at 60.96 49.53 0)
      (effects (font (size 1.27 1.27) (thickness 0.15)) (justify left bottom) hide)
    )
    (property "MPN" "GRM155R61H104KE14D" (at 63.5 49.53 0)
      (effects (font (size 1.27 1.27) (thickness 0.15)) (justify left bottom) hide)
    )
    (property "Val" "100n" (at 86.995 69.215 90)
      (effects (font (size 1.27 1.27) (thickness 0.15)) (justify right))
    )
    (property "License" "Apache-2.0" (at 58.42 49.53 0)
      (effects (font (size 1.27 1.27) (thickness 0.15)) (justify left bottom) hide)
    )
    (property "Author" "Antmicro" (at 55.88 49.53 0)
      (effects (font (size 1.27 1.27) (thickness 0.15)) (justify left bottom) hide)
    )
    (property "Voltage" "50V" (at 53.34 49.53 0)
      (effects (font (size 1.27 1.27)) (justify left bottom) hide)
    )
    (property "Dielectric" "X5R" (at 50.8 49.53 0)
      (effects (font (size 1.27 1.27)) (justify left bottom) hide)
    )
    (pin "1")
    (pin "2")
    (instances
      (project "d1600e-psu-breakout-board"
        (path ""
          (reference "C9") (unit 1)
        )
      )
    )
  )

  (symbol (lib_name "C_100n_0402_10") (lib_id "antmicroCapacitors0402:C_100n_0402") (at 72.39 69.85 270) (mirror x) (unit 1)
    (in_bom yes) (on_board yes) (dnp no)
    (property "Reference" "C10" (at 76.835 65.405 90)
      (effects (font (size 1.27 1.27)) (justify right))
    )
    (property "Value" "C_100n_0402" (at 62.23 49.53 0)
      (effects (font (size 1.27 1.27) (thickness 0.15)) (justify left bottom) hide)
    )
    (property "Footprint" "antmicro-footprints:C_0402_1005Metric" (at 59.69 49.53 0)
      (effects (font (size 1.27 1.27) (thickness 0.15)) (justify left bottom) hide)
    )
    (property "Datasheet" "https://www.murata.com/products/productdetail?partno=GRM155R61H104KE14%23" (at 57.15 49.53 0)
      (effects (font (size 1.27 1.27) (thickness 0.15)) (justify left bottom) hide)
    )
    (property "Manufacturer" "Murata" (at 52.07 49.53 0)
      (effects (font (size 1.27 1.27) (thickness 0.15)) (justify left bottom) hide)
    )
    (property "MPN" "GRM155R61H104KE14D" (at 54.61 49.53 0)
      (effects (font (size 1.27 1.27) (thickness 0.15)) (justify left bottom) hide)
    )
    (property "Val" "100n" (at 78.105 69.215 90)
      (effects (font (size 1.27 1.27) (thickness 0.15)) (justify right))
    )
    (property "License" "Apache-2.0" (at 49.53 49.53 0)
      (effects (font (size 1.27 1.27) (thickness 0.15)) (justify left bottom) hide)
    )
    (property "Author" "Antmicro" (at 46.99 49.53 0)
      (effects (font (size 1.27 1.27) (thickness 0.15)) (justify left bottom) hide)
    )
    (property "Voltage" "50V" (at 44.45 49.53 0)
      (effects (font (size 1.27 1.27)) (justify left bottom) hide)
    )
    (property "Dielectric" "X5R" (at 41.91 49.53 0)
      (effects (font (size 1.27 1.27)) (justify left bottom) hide)
    )
    (pin "1")
    (pin "2")
    (instances
      (project "d1600e-psu-breakout-board"
        (path ""
          (reference "C10") (unit 1)
        )
      )
    )
  )

  (symbol (lib_name "C_100n_0402_9") (lib_id "antmicroCapacitors0402:C_100n_0402") (at 88.9 69.85 270) (mirror x) (unit 1)
    (in_bom yes) (on_board yes) (dnp no)
    (property "Reference" "C8" (at 89.535 65.405 90)
      (effects (font (size 1.27 1.27)) (justify left))
    )
    (property "Value" "C_100n_0402" (at 78.74 49.53 0)
      (effects (font (size 1.27 1.27) (thickness 0.15)) (justify left bottom) hide)
    )
    (property "Footprint" "antmicro-footprints:C_0402_1005Metric" (at 76.2 49.53 0)
      (effects (font (size 1.27 1.27) (thickness 0.15)) (justify left bottom) hide)
    )
    (property "Datasheet" "https://www.murata.com/products/productdetail?partno=GRM155R61H104KE14%23" (at 73.66 49.53 0)
      (effects (font (size 1.27 1.27) (thickness 0.15)) (justify left bottom) hide)
    )
    (property "Manufacturer" "Murata" (at 68.58 49.53 0)
      (effects (font (size 1.27 1.27) (thickness 0.15)) (justify left bottom) hide)
    )
    (property "MPN" "GRM155R61H104KE14D" (at 71.12 49.53 0)
      (effects (font (size 1.27 1.27) (thickness 0.15)) (justify left bottom) hide)
    )
    (property "Val" "100n" (at 94.615 69.215 90)
      (effects (font (size 1.27 1.27) (thickness 0.15)) (justify right))
    )
    (property "License" "Apache-2.0" (at 66.04 49.53 0)
      (effects (font (size 1.27 1.27) (thickness 0.15)) (justify left bottom) hide)
    )
    (property "Author" "Antmicro" (at 63.5 49.53 0)
      (effects (font (size 1.27 1.27) (thickness 0.15)) (justify left bottom) hide)
    )
    (property "Voltage" "50V" (at 60.96 49.53 0)
      (effects (font (size 1.27 1.27)) (justify left bottom) hide)
    )
    (property "Dielectric" "X5R" (at 58.42 49.53 0)
      (effects (font (size 1.27 1.27)) (justify left bottom) hide)
    )
    (pin "1")
    (pin "2")
    (instances
      (project "d1600e-psu-breakout-board"
        (path ""
          (reference "C8") (unit 1)
        )
      )
    )
  )

  (symbol (lib_id "antmicroResistors0603:R_0R_0603") (at 370.84 36.83 0) (unit 1)
    (in_bom yes) (on_board yes) (dnp no)
    (property "Reference" "R8" (at 373.38 31.75 0)
      (effects (font (size 1.27 1.27)))
    )
    (property "Value" "R_0R_0603" (at 391.16 49.53 0)
      (effects (font (size 1.27 1.27) (thickness 0.15)) (justify left bottom) hide)
    )
    (property "Footprint" "antmicro-footprints:R_0603_1608Metric" (at 391.16 52.07 0)
      (effects (font (size 1.27 1.27) (thickness 0.15)) (justify left bottom) hide)
    )
    (property "Datasheet" "https://www.bourns.com/docs/product-datasheets/cr.pdf?sfvrsn=574d41f6_14" (at 391.16 54.61 0)
      (effects (font (size 1.27 1.27) (thickness 0.15)) (justify left bottom) hide)
    )
    (property "Manufacturer" "Bourns" (at 391.16 59.69 0)
      (effects (font (size 1.27 1.27) (thickness 0.15)) (justify left bottom) hide)
    )
    (property "MPN" "CR0603-J/-000ELF" (at 391.16 57.15 0)
      (effects (font (size 1.27 1.27) (thickness 0.15)) (justify left bottom) hide)
    )
    (property "Val" "0R" (at 373.38 34.29 0)
      (effects (font (size 1.27 1.27) (thickness 0.15)))
    )
    (property "License" "Apache-2.0" (at 391.16 62.23 0)
      (effects (font (size 1.27 1.27) (thickness 0.15)) (justify left bottom) hide)
    )
    (property "Author" "Antmicro" (at 391.16 64.77 0)
      (effects (font (size 1.27 1.27) (thickness 0.15)) (justify left bottom) hide)
    )
    (property "Tolerance" "~" (at 391.16 46.99 0)
      (effects (font (size 1.27 1.27)) (justify left bottom) hide)
    )
    (property "Current" "1A" (at 391.16 67.31 0)
      (effects (font (size 1.27 1.27) (thickness 0.15)) (justify left bottom) hide)
    )
    (pin "1")
    (pin "2")
    (instances
      (project "d1600e-psu-breakout-board"
        (path ""
          (reference "R8") (unit 1)
        )
      )
    )
  )

  (symbol (lib_id "antmicroCapacitors0402:C_100n_0402") (at 292.1 31.75 0) (unit 1)
    (in_bom yes) (on_board yes) (dnp no)
    (property "Reference" "C17" (at 298.45 30.48 0)
      (effects (font (size 1.27 1.27)))
    )
    (property "Value" "C_100n_0402" (at 312.42 41.91 0)
      (effects (font (size 1.27 1.27) (thickness 0.15)) (justify left bottom) hide)
    )
    (property "Footprint" "antmicro-footprints:C_0402_1005Metric" (at 312.42 44.45 0)
      (effects (font (size 1.27 1.27) (thickness 0.15)) (justify left bottom) hide)
    )
    (property "Datasheet" "https://www.murata.com/products/productdetail?partno=GRM155R61H104KE14%23" (at 312.42 46.99 0)
      (effects (font (size 1.27 1.27) (thickness 0.15)) (justify left bottom) hide)
    )
    (property "Manufacturer" "Murata" (at 312.42 52.07 0)
      (effects (font (size 1.27 1.27) (thickness 0.15)) (justify left bottom) hide)
    )
    (property "MPN" "GRM155R61H104KE14D" (at 312.42 49.53 0)
      (effects (font (size 1.27 1.27) (thickness 0.15)) (justify left bottom) hide)
    )
    (property "Val" "100n" (at 290.83 30.48 0)
      (effects (font (size 1.27 1.27) (thickness 0.15)))
    )
    (property "License" "Apache-2.0" (at 312.42 54.61 0)
      (effects (font (size 1.27 1.27) (thickness 0.15)) (justify left bottom) hide)
    )
    (property "Author" "Antmicro" (at 312.42 57.15 0)
      (effects (font (size 1.27 1.27) (thickness 0.15)) (justify left bottom) hide)
    )
    (property "Voltage" "50V" (at 312.42 59.69 0)
      (effects (font (size 1.27 1.27)) (justify left bottom) hide)
    )
    (property "Dielectric" "X5R" (at 312.42 62.23 0)
      (effects (font (size 1.27 1.27)) (justify left bottom) hide)
    )
    (pin "1")
    (pin "2")
    (instances
      (project "d1600e-psu-breakout-board"
        (path ""
          (reference "C17") (unit 1)
        )
      )
    )
  )

  (symbol (lib_id "antmicroTVSDiodes:PESD5V0S2BQA") (at 335.28 82.55 0) (unit 1)
    (in_bom yes) (on_board yes) (dnp no)
    (property "Reference" "D1" (at 341.63 76.2 0)
      (effects (font (size 1.27 1.27)) (justify left))
    )
    (property "Value" "PESD5V0S2BQA" (at 363.22 92.71 0)
      (effects (font (size 1.27 1.27) (thickness 0.15)) (justify left bottom) hide)
    )
    (property "Footprint" "antmicro-footprints:TPD2E009DRTR" (at 363.22 95.25 0)
      (effects (font (size 1.27 1.27) (thickness 0.15)) (justify left bottom) hide)
    )
    (property "Datasheet" "https://4donline.ihs.com/images/VipMasterIC/IC/NEXP/NEXP-S-A0003105620/NEXP-S-A0003107857-1.pdf?hkey=6D3A4C79FDBF58556ACFDE234799DDF0" (at 363.22 97.79 0)
      (effects (font (size 1.27 1.27) (thickness 0.15)) (justify left bottom) hide)
    )
    (property "MPN" "PESD5V0S2BQA" (at 336.55 78.74 0)
      (effects (font (size 1.27 1.27) (thickness 0.15)) (justify left))
    )
    (property "Manufacturer" "Nexperia" (at 363.22 90.17 0)
      (effects (font (size 1.27 1.27) (thickness 0.15)) (justify left bottom) hide)
    )
    (property "Author" "Antmicro" (at 363.22 100.33 0)
      (effects (font (size 1.27 1.27) (thickness 0.15)) (justify left bottom) hide)
    )
    (property "License" "Apache-2.0" (at 363.22 102.87 0)
      (effects (font (size 1.27 1.27) (thickness 0.15)) (justify left bottom) hide)
    )
    (pin "1")
    (pin "2")
    (pin "3")
    (instances
      (project "d1600e-psu-breakout-board"
        (path ""
          (reference "D1") (unit 1)
        )
      )
    )
  )

  (symbol (lib_id "antmicroFerriteBeadsandChips:FB_600Z_0.5A_Murata-BLM18AG_0603") (at 308.61 87.63 270) (unit 1)
    (in_bom yes) (on_board yes) (dnp no)
    (property "Reference" "FB3" (at 309.88 88.9 90)
      (effects (font (size 1.27 1.27)) (justify left))
    )
    (property "Value" "FB_600Z_0.5A_Murata-BLM18AG_0603" (at 306.07 102.87 0)
      (effects (font (size 1.27 1.27) (thickness 0.15)) (justify left bottom) hide)
    )
    (property "Footprint" "antmicro-footprints:FB_0603_1608Metric" (at 300.99 102.87 0)
      (effects (font (size 1.27 1.27) (thickness 0.15)) (justify left bottom) hide)
    )
    (property "Datasheet" "https://www.murata.com/en-us/products/productdata/8796738650142/ENFA0003.pdf" (at 298.45 102.87 0)
      (effects (font (size 1.27 1.27) (thickness 0.15)) (justify left bottom) hide)
    )
    (property "MPN" "BLM18AG601SN1D" (at 295.91 102.87 0)
      (effects (font (size 1.27 1.27) (thickness 0.15)) (justify left bottom) hide)
    )
    (property "Manufacturer" "Murata" (at 293.37 102.87 0)
      (effects (font (size 1.27 1.27) (thickness 0.15)) (justify left bottom) hide)
    )
    (property "Val" "600Z/0.5A" (at 309.88 92.71 90)
      (effects (font (size 1.27 1.27)) (justify left))
    )
    (property "Current" "" (at 285.75 107.95 0)
      (effects (font (size 1.27 1.27) (thickness 0.15)) (justify left bottom) hide)
    )
    (property "Author" "Antmicro" (at 290.83 102.87 0)
      (effects (font (size 1.27 1.27) (thickness 0.15)) (justify left bottom) hide)
    )
    (property "License" "Apache-2.0" (at 288.29 102.87 0)
      (effects (font (size 1.27 1.27) (thickness 0.15)) (justify left bottom) hide)
    )
    (pin "1")
    (pin "2")
    (instances
      (project "d1600e-psu-breakout-board"
        (path ""
          (reference "FB3") (unit 1)
        )
      )
    )
  )

  (symbol (lib_id "antmicroLEDIndicationDiscrete:LED_G_0603_LG_L29K-G2J1-24-Z") (at 276.86 219.71 90) (unit 1)
    (in_bom yes) (on_board yes) (dnp no)
    (property "Reference" "D2" (at 278.13 215.9 90)
      (effects (font (size 1.27 1.27)) (justify right))
    )
    (property "Value" "LED_G_0603_LG_L29K-G2J1-24-Z" (at 284.48 199.39 0)
      (effects (font (size 1.27 1.27) (thickness 0.15)) (justify left bottom) hide)
    )
    (property "Footprint" "antmicro-footprints:LED_0603_1608Metric_G" (at 287.02 199.39 0)
      (effects (font (size 1.27 1.27) (thickness 0.15)) (justify left bottom) hide)
    )
    (property "Datasheet" "https://look.ams-osram.com/m/19ee86b3ae0ee95b/original/LG-L29K.pdf" (at 289.56 199.39 0)
      (effects (font (size 1.27 1.27) (thickness 0.15)) (justify left bottom) hide)
    )
    (property "MPN" "LG L29K-G2J1-24-Z" (at 292.1 199.39 0)
      (effects (font (size 1.27 1.27) (thickness 0.15)) (justify left bottom) hide)
    )
    (property "Manufacturer" "OSRAM" (at 294.64 199.39 0)
      (effects (font (size 1.27 1.27) (thickness 0.15)) (justify left bottom) hide)
    )
    (property "Color" "Green" (at 278.13 218.44 90)
      (effects (font (size 1.27 1.27)) (justify right))
    )
    (property "Author" "Antmicro" (at 297.18 199.39 0)
      (effects (font (size 1.27 1.27) (thickness 0.15)) (justify left bottom) hide)
    )
    (property "License" "Apache-2.0" (at 299.72 199.39 0)
      (effects (font (size 1.27 1.27) (thickness 0.15)) (justify left bottom) hide)
    )
    (pin "1")
    (pin "2")
    (instances
      (project "d1600e-psu-breakout-board"
        (path ""
          (reference "D2") (unit 1)
        )
      )
    )
  )

  (symbol (lib_id "antmicroResistors0402:R_330R_0402") (at 276.86 205.74 270) (unit 1)
    (in_bom yes) (on_board yes) (dnp no)
    (property "Reference" "R7" (at 278.13 207.01 90)
      (effects (font (size 1.27 1.27)) (justify left))
    )
    (property "Value" "R_330R_0402" (at 264.16 226.06 0)
      (effects (font (size 1.27 1.27) (thickness 0.15)) (justify left bottom) hide)
    )
    (property "Footprint" "antmicro-footprints:R_0402_1005Metric" (at 261.62 226.06 0)
      (effects (font (size 1.27 1.27) (thickness 0.15)) (justify left bottom) hide)
    )
    (property "Datasheet" "https://www.bourns.com/docs/product-datasheets/cr.pdf" (at 259.08 226.06 0)
      (effects (font (size 1.27 1.27) (thickness 0.15)) (justify left bottom) hide)
    )
    (property "Manufacturer" "Bourns" (at 254 226.06 0)
      (effects (font (size 1.27 1.27) (thickness 0.15)) (justify left bottom) hide)
    )
    (property "MPN" "CR0402-FX-3300GLF" (at 256.54 226.06 0)
      (effects (font (size 1.27 1.27) (thickness 0.15)) (justify left bottom) hide)
    )
    (property "Val" "330R" (at 278.13 209.55 90)
      (effects (font (size 1.27 1.27) (thickness 0.15)) (justify left))
    )
    (property "License" "Apache-2.0" (at 251.46 226.06 0)
      (effects (font (size 1.27 1.27) (thickness 0.15)) (justify left bottom) hide)
    )
    (property "Author" "Antmicro" (at 248.92 226.06 0)
      (effects (font (size 1.27 1.27) (thickness 0.15)) (justify left bottom) hide)
    )
    (property "Tolerance" "1%" (at 266.7 226.06 0)
      (effects (font (size 1.27 1.27)) (justify left bottom) hide)
    )
    (pin "1")
    (pin "2")
    (instances
      (project "d1600e-psu-breakout-board"
        (path ""
          (reference "R7") (unit 1)
        )
      )
    )
  )

  (symbol (lib_id "antmicroTestPoints:TP_1mm_SMD") (at 354.33 207.01 0) (unit 1)
    (in_bom no) (on_board yes) (dnp no) (fields_autoplaced)
    (property "Reference" "3V3" (at 359.41 207.01 0)
      (effects (font (size 1.27 1.27)) (justify left))
    )
    (property "Value" "TP_1mm_SMD" (at 369.57 214.63 0)
      (effects (font (size 1.27 1.27) (thickness 0.15)) (justify left bottom) hide)
    )
    (property "Footprint" "antmicro-footprints:TP_SMD_1mm" (at 369.57 217.17 0)
      (effects (font (size 1.27 1.27) (thickness 0.15)) (justify left bottom) hide)
    )
    (property "Datasheet" "" (at 372.11 219.71 0)
      (effects (font (size 1.27 1.27) (thickness 0.15)) (justify left bottom) hide)
    )
    (property "MPN" "" (at 354.33 207.01 0)
      (effects (font (size 1.27 1.27)) hide)
    )
    (property "Manufacturer" "" (at 354.33 207.01 0)
      (effects (font (size 1.27 1.27)) hide)
    )
    (property "Author" "Antmicro" (at 369.57 222.25 0)
      (effects (font (size 1.27 1.27) (thickness 0.15)) (justify left bottom) hide)
    )
    (property "License" "Apache-2.0" (at 369.57 224.79 0)
      (effects (font (size 1.27 1.27) (thickness 0.15)) (justify left bottom) hide)
    )
    (pin "1")
    (instances
      (project "d1600e-psu-breakout-board"
        (path ""
          (reference "3V3") (unit 1)
        )
      )
    )
  )

  (symbol (lib_id "antmicroTestPoints:TP_1mm_SMD") (at 354.33 210.82 0) (unit 1)
    (in_bom no) (on_board yes) (dnp no) (fields_autoplaced)
    (property "Reference" "5V_USB1" (at 359.41 210.82 0)
      (effects (font (size 1.27 1.27)) (justify left))
    )
    (property "Value" "TP_1mm_SMD" (at 369.57 218.44 0)
      (effects (font (size 1.27 1.27) (thickness 0.15)) (justify left bottom) hide)
    )
    (property "Footprint" "antmicro-footprints:TP_SMD_1mm" (at 369.57 220.98 0)
      (effects (font (size 1.27 1.27) (thickness 0.15)) (justify left bottom) hide)
    )
    (property "Datasheet" "" (at 372.11 223.52 0)
      (effects (font (size 1.27 1.27) (thickness 0.15)) (justify left bottom) hide)
    )
    (property "MPN" "" (at 354.33 210.82 0)
      (effects (font (size 1.27 1.27)) hide)
    )
    (property "Manufacturer" "" (at 354.33 210.82 0)
      (effects (font (size 1.27 1.27)) hide)
    )
    (property "Author" "Antmicro" (at 369.57 226.06 0)
      (effects (font (size 1.27 1.27) (thickness 0.15)) (justify left bottom) hide)
    )
    (property "License" "Apache-2.0" (at 369.57 228.6 0)
      (effects (font (size 1.27 1.27) (thickness 0.15)) (justify left bottom) hide)
    )
    (pin "1")
    (instances
      (project "d1600e-psu-breakout-board"
        (path ""
          (reference "5V_USB1") (unit 1)
        )
      )
    )
  )

  (symbol (lib_id "antmicroOptoisolatorsLogicOutput:ISO1641") (at 106.68 238.76 0) (unit 1)
    (in_bom yes) (on_board yes) (dnp no)
    (property "Reference" "U2" (at 116.84 233.68 0)
      (effects (font (size 1.27 1.27)))
    )
    (property "Value" "ISO1641" (at 142.24 248.92 0)
      (effects (font (size 1.27 1.27) (thickness 0.15)) (justify left bottom) hide)
    )
    (property "Footprint" "antmicro-footprints:SOIC-8_3.9x4.9x1.75mm_P1.27mm" (at 142.24 251.46 0)
      (effects (font (size 1.27 1.27) (thickness 0.15)) (justify left bottom) hide)
    )
    (property "Datasheet" "https://www.ti.com/lit/ds/symlink/iso1641.pdf?ts=1649669035432&ref_url=https%253A%252F%252Fwww.ti.com%252Fproduct%252FISO1641" (at 142.24 254 0)
      (effects (font (size 1.27 1.27) (thickness 0.15)) (justify left bottom) hide)
    )
    (property "MPN" "ISO1641BDR" (at 116.84 236.22 0)
      (effects (font (size 1.27 1.27) (thickness 0.15)))
    )
    (property "Manufacturer" "Texas Instruments" (at 142.24 256.54 0)
      (effects (font (size 1.27 1.27) (thickness 0.15)) (justify left bottom) hide)
    )
    (property "Author" "Antmicro" (at 142.24 259.08 0)
      (effects (font (size 1.27 1.27) (thickness 0.15)) (justify left bottom) hide)
    )
    (property "License" "Apache-2.0" (at 142.24 261.62 0)
      (effects (font (size 1.27 1.27) (thickness 0.15)) (justify left bottom) hide)
    )
    (pin "1")
    (pin "2")
    (pin "3")
    (pin "4")
    (pin "5")
    (pin "6")
    (pin "7")
    (pin "8")
    (instances
      (project "d1600e-psu-breakout-board"
        (path ""
          (reference "U2") (unit 1)
        )
      )
    )
  )

  (symbol (lib_id "antmicropower:GND") (at 129.54 254 0) (unit 1)
    (in_bom yes) (on_board yes) (dnp no)
    (property "Reference" "#PWR012" (at 129.54 260.35 0)
      (effects (font (size 1.27 1.27)) hide)
    )
    (property "Value" "GND" (at 129.54 257.81 0)
      (effects (font (size 1.27 1.27) (thickness 0.15)))
    )
    (property "Footprint" "" (at 138.43 261.62 0)
      (effects (font (size 1.27 1.27) (thickness 0.15)) (justify left bottom) hide)
    )
    (property "Datasheet" "" (at 138.43 266.7 0)
      (effects (font (size 1.27 1.27) (thickness 0.15)) (justify left bottom) hide)
    )
    (property "Author" "Antmicro" (at 138.43 261.62 0)
      (effects (font (size 1.27 1.27) (thickness 0.15)) (justify left bottom) hide)
    )
    (property "License" "Apache-2.0" (at 138.43 264.16 0)
      (effects (font (size 1.27 1.27) (thickness 0.15)) (justify left bottom) hide)
    )
    (pin "1")
    (instances
      (project "d1600e-psu-breakout-board"
        (path ""
          (reference "#PWR012") (unit 1)
        )
      )
    )
  )

  (symbol (lib_name "C_100n_0402_11") (lib_id "antmicroCapacitors0402:C_100n_0402") (at 86.36 247.65 90) (unit 1)
    (in_bom yes) (on_board yes) (dnp no)
    (property "Reference" "C16" (at 86.995 243.205 90)
      (effects (font (size 1.27 1.27)) (justify right))
    )
    (property "Value" "C_100n_0402" (at 96.52 227.33 0)
      (effects (font (size 1.27 1.27) (thickness 0.15)) (justify left bottom) hide)
    )
    (property "Footprint" "antmicro-footprints:C_0402_1005Metric" (at 99.06 227.33 0)
      (effects (font (size 1.27 1.27) (thickness 0.15)) (justify left bottom) hide)
    )
    (property "Datasheet" "https://www.murata.com/products/productdetail?partno=GRM155R61H104KE14%23" (at 101.6 227.33 0)
      (effects (font (size 1.27 1.27) (thickness 0.15)) (justify left bottom) hide)
    )
    (property "Manufacturer" "Murata" (at 106.68 227.33 0)
      (effects (font (size 1.27 1.27) (thickness 0.15)) (justify left bottom) hide)
    )
    (property "MPN" "GRM155R61H104KE14D" (at 104.14 227.33 0)
      (effects (font (size 1.27 1.27) (thickness 0.15)) (justify left bottom) hide)
    )
    (property "Val" "100n" (at 86.995 247.015 90)
      (effects (font (size 1.27 1.27) (thickness 0.15)) (justify right))
    )
    (property "License" "Apache-2.0" (at 109.22 227.33 0)
      (effects (font (size 1.27 1.27) (thickness 0.15)) (justify left bottom) hide)
    )
    (property "Author" "Antmicro" (at 111.76 227.33 0)
      (effects (font (size 1.27 1.27) (thickness 0.15)) (justify left bottom) hide)
    )
    (property "Voltage" "50V" (at 114.3 227.33 0)
      (effects (font (size 1.27 1.27)) (justify left bottom) hide)
    )
    (property "Dielectric" "X5R" (at 116.84 227.33 0)
      (effects (font (size 1.27 1.27)) (justify left bottom) hide)
    )
    (pin "1")
    (pin "2")
    (instances
      (project "d1600e-psu-breakout-board"
        (path ""
          (reference "C16") (unit 1)
        )
      )
    )
  )

  (symbol (lib_name "C_100n_0402_12") (lib_id "antmicroCapacitors0402:C_100n_0402") (at 153.67 243.84 270) (unit 1)
    (in_bom yes) (on_board yes) (dnp no)
    (property "Reference" "C18" (at 154.305 244.475 90)
      (effects (font (size 1.27 1.27)) (justify left))
    )
    (property "Value" "C_100n_0402" (at 143.51 264.16 0)
      (effects (font (size 1.27 1.27) (thickness 0.15)) (justify left bottom) hide)
    )
    (property "Footprint" "antmicro-footprints:C_0402_1005Metric" (at 140.97 264.16 0)
      (effects (font (size 1.27 1.27) (thickness 0.15)) (justify left bottom) hide)
    )
    (property "Datasheet" "https://www.murata.com/products/productdetail?partno=GRM155R61H104KE14%23" (at 138.43 264.16 0)
      (effects (font (size 1.27 1.27) (thickness 0.15)) (justify left bottom) hide)
    )
    (property "Manufacturer" "Murata" (at 133.35 264.16 0)
      (effects (font (size 1.27 1.27) (thickness 0.15)) (justify left bottom) hide)
    )
    (property "MPN" "GRM155R61H104KE14D" (at 135.89 264.16 0)
      (effects (font (size 1.27 1.27) (thickness 0.15)) (justify left bottom) hide)
    )
    (property "Val" "100n" (at 154.305 248.285 90)
      (effects (font (size 1.27 1.27) (thickness 0.15)) (justify left))
    )
    (property "License" "Apache-2.0" (at 130.81 264.16 0)
      (effects (font (size 1.27 1.27) (thickness 0.15)) (justify left bottom) hide)
    )
    (property "Author" "Antmicro" (at 128.27 264.16 0)
      (effects (font (size 1.27 1.27) (thickness 0.15)) (justify left bottom) hide)
    )
    (property "Voltage" "50V" (at 125.73 264.16 0)
      (effects (font (size 1.27 1.27)) (justify left bottom) hide)
    )
    (property "Dielectric" "X5R" (at 123.19 264.16 0)
      (effects (font (size 1.27 1.27)) (justify left bottom) hide)
    )
    (pin "1")
    (pin "2")
    (instances
      (project "d1600e-psu-breakout-board"
        (path ""
          (reference "C18") (unit 1)
        )
      )
    )
  )

  (symbol (lib_id "antmicropower:GNDD") (at 104.14 254 0) (unit 1)
    (in_bom yes) (on_board yes) (dnp no) (fields_autoplaced)
    (property "Reference" "#PWR06" (at 104.14 260.35 0)
      (effects (font (size 1.27 1.27)) hide)
    )
    (property "Value" "GNDD" (at 104.14 257.81 0)
      (effects (font (size 1.27 1.27) (thickness 0.15)))
    )
    (property "Footprint" "" (at 119.38 264.16 0)
      (effects (font (size 1.27 1.27) (thickness 0.15)) (justify left bottom) hide)
    )
    (property "Datasheet" "" (at 119.38 266.7 0)
      (effects (font (size 1.27 1.27) (thickness 0.15)) (justify left bottom) hide)
    )
    (property "Author" "Antmicro" (at 119.38 261.62 0)
      (effects (font (size 1.27 1.27) (thickness 0.15)) (justify left bottom) hide)
    )
    (property "License" "Apache-2.0" (at 119.38 264.16 0)
      (effects (font (size 1.27 1.27) (thickness 0.15)) (justify left bottom) hide)
    )
    (pin "1")
    (instances
      (project "d1600e-psu-breakout-board"
        (path ""
          (reference "#PWR06") (unit 1)
        )
      )
    )
  )

  (symbol (lib_id "antmicropower:GND") (at 153.67 254 0) (unit 1)
    (in_bom yes) (on_board yes) (dnp no)
    (property "Reference" "#PWR032" (at 153.67 260.35 0)
      (effects (font (size 1.27 1.27)) hide)
    )
    (property "Value" "GND" (at 153.67 257.81 0)
      (effects (font (size 1.27 1.27) (thickness 0.15)))
    )
    (property "Footprint" "" (at 162.56 261.62 0)
      (effects (font (size 1.27 1.27) (thickness 0.15)) (justify left bottom) hide)
    )
    (property "Datasheet" "" (at 162.56 266.7 0)
      (effects (font (size 1.27 1.27) (thickness 0.15)) (justify left bottom) hide)
    )
    (property "Author" "Antmicro" (at 162.56 261.62 0)
      (effects (font (size 1.27 1.27) (thickness 0.15)) (justify left bottom) hide)
    )
    (property "License" "Apache-2.0" (at 162.56 264.16 0)
      (effects (font (size 1.27 1.27) (thickness 0.15)) (justify left bottom) hide)
    )
    (pin "1")
    (instances
      (project "d1600e-psu-breakout-board"
        (path ""
          (reference "#PWR032") (unit 1)
        )
      )
    )
  )

  (symbol (lib_id "antmicropower:GNDD") (at 86.36 254 0) (unit 1)
    (in_bom yes) (on_board yes) (dnp no) (fields_autoplaced)
    (property "Reference" "#PWR028" (at 86.36 260.35 0)
      (effects (font (size 1.27 1.27)) hide)
    )
    (property "Value" "GNDD" (at 86.36 257.81 0)
      (effects (font (size 1.27 1.27) (thickness 0.15)))
    )
    (property "Footprint" "" (at 101.6 264.16 0)
      (effects (font (size 1.27 1.27) (thickness 0.15)) (justify left bottom) hide)
    )
    (property "Datasheet" "" (at 101.6 266.7 0)
      (effects (font (size 1.27 1.27) (thickness 0.15)) (justify left bottom) hide)
    )
    (property "Author" "Antmicro" (at 101.6 261.62 0)
      (effects (font (size 1.27 1.27) (thickness 0.15)) (justify left bottom) hide)
    )
    (property "License" "Apache-2.0" (at 101.6 264.16 0)
      (effects (font (size 1.27 1.27) (thickness 0.15)) (justify left bottom) hide)
    )
    (pin "1")
    (instances
      (project "d1600e-psu-breakout-board"
        (path ""
          (reference "#PWR028") (unit 1)
        )
      )
    )
  )

  (symbol (lib_id "antmicropower:GNDD") (at 63.5 72.39 0) (mirror y) (unit 1)
    (in_bom yes) (on_board yes) (dnp no) (fields_autoplaced)
    (property "Reference" "#PWR021" (at 63.5 78.74 0)
      (effects (font (size 1.27 1.27)) hide)
    )
    (property "Value" "GNDD" (at 63.5 76.2 0)
      (effects (font (size 1.27 1.27) (thickness 0.15)))
    )
    (property "Footprint" "" (at 48.26 82.55 0)
      (effects (font (size 1.27 1.27) (thickness 0.15)) (justify left bottom) hide)
    )
    (property "Datasheet" "" (at 48.26 85.09 0)
      (effects (font (size 1.27 1.27) (thickness 0.15)) (justify left bottom) hide)
    )
    (property "Author" "Antmicro" (at 48.26 80.01 0)
      (effects (font (size 1.27 1.27) (thickness 0.15)) (justify left bottom) hide)
    )
    (property "License" "Apache-2.0" (at 48.26 82.55 0)
      (effects (font (size 1.27 1.27) (thickness 0.15)) (justify left bottom) hide)
    )
    (pin "1")
    (instances
      (project "d1600e-psu-breakout-board"
        (path ""
          (reference "#PWR021") (unit 1)
        )
      )
    )
  )

  (symbol (lib_id "antmicropower:GNDD") (at 72.39 72.39 0) (mirror y) (unit 1)
    (in_bom yes) (on_board yes) (dnp no) (fields_autoplaced)
    (property "Reference" "#PWR018" (at 72.39 78.74 0)
      (effects (font (size 1.27 1.27)) hide)
    )
    (property "Value" "GNDD" (at 72.39 76.2 0)
      (effects (font (size 1.27 1.27) (thickness 0.15)))
    )
    (property "Footprint" "" (at 57.15 82.55 0)
      (effects (font (size 1.27 1.27) (thickness 0.15)) (justify left bottom) hide)
    )
    (property "Datasheet" "" (at 57.15 85.09 0)
      (effects (font (size 1.27 1.27) (thickness 0.15)) (justify left bottom) hide)
    )
    (property "Author" "Antmicro" (at 57.15 80.01 0)
      (effects (font (size 1.27 1.27) (thickness 0.15)) (justify left bottom) hide)
    )
    (property "License" "Apache-2.0" (at 57.15 82.55 0)
      (effects (font (size 1.27 1.27) (thickness 0.15)) (justify left bottom) hide)
    )
    (pin "1")
    (instances
      (project "d1600e-psu-breakout-board"
        (path ""
          (reference "#PWR018") (unit 1)
        )
      )
    )
  )

  (symbol (lib_id "antmicropower:GNDD") (at 81.28 72.39 0) (mirror y) (unit 1)
    (in_bom yes) (on_board yes) (dnp no) (fields_autoplaced)
    (property "Reference" "#PWR017" (at 81.28 78.74 0)
      (effects (font (size 1.27 1.27)) hide)
    )
    (property "Value" "GNDD" (at 81.28 76.2 0)
      (effects (font (size 1.27 1.27) (thickness 0.15)))
    )
    (property "Footprint" "" (at 66.04 82.55 0)
      (effects (font (size 1.27 1.27) (thickness 0.15)) (justify left bottom) hide)
    )
    (property "Datasheet" "" (at 66.04 85.09 0)
      (effects (font (size 1.27 1.27) (thickness 0.15)) (justify left bottom) hide)
    )
    (property "Author" "Antmicro" (at 66.04 80.01 0)
      (effects (font (size 1.27 1.27) (thickness 0.15)) (justify left bottom) hide)
    )
    (property "License" "Apache-2.0" (at 66.04 82.55 0)
      (effects (font (size 1.27 1.27) (thickness 0.15)) (justify left bottom) hide)
    )
    (pin "1")
    (instances
      (project "d1600e-psu-breakout-board"
        (path ""
          (reference "#PWR017") (unit 1)
        )
      )
    )
  )

  (symbol (lib_id "antmicropower:GNDD") (at 88.9 72.39 0) (mirror y) (unit 1)
    (in_bom yes) (on_board yes) (dnp no) (fields_autoplaced)
    (property "Reference" "#PWR015" (at 88.9 78.74 0)
      (effects (font (size 1.27 1.27)) hide)
    )
    (property "Value" "GNDD" (at 88.9 76.2 0)
      (effects (font (size 1.27 1.27) (thickness 0.15)))
    )
    (property "Footprint" "" (at 73.66 82.55 0)
      (effects (font (size 1.27 1.27) (thickness 0.15)) (justify left bottom) hide)
    )
    (property "Datasheet" "" (at 73.66 85.09 0)
      (effects (font (size 1.27 1.27) (thickness 0.15)) (justify left bottom) hide)
    )
    (property "Author" "Antmicro" (at 73.66 80.01 0)
      (effects (font (size 1.27 1.27) (thickness 0.15)) (justify left bottom) hide)
    )
    (property "License" "Apache-2.0" (at 73.66 82.55 0)
      (effects (font (size 1.27 1.27) (thickness 0.15)) (justify left bottom) hide)
    )
    (pin "1")
    (instances
      (project "d1600e-psu-breakout-board"
        (path ""
          (reference "#PWR015") (unit 1)
        )
      )
    )
  )

  (symbol (lib_id "antmicropower:GNDD") (at 53.34 66.04 0) (unit 1)
    (in_bom yes) (on_board yes) (dnp no) (fields_autoplaced)
    (property "Reference" "#PWR014" (at 53.34 72.39 0)
      (effects (font (size 1.27 1.27)) hide)
    )
    (property "Value" "GNDD" (at 53.34 69.85 0)
      (effects (font (size 1.27 1.27) (thickness 0.15)))
    )
    (property "Footprint" "" (at 68.58 76.2 0)
      (effects (font (size 1.27 1.27) (thickness 0.15)) (justify left bottom) hide)
    )
    (property "Datasheet" "" (at 68.58 78.74 0)
      (effects (font (size 1.27 1.27) (thickness 0.15)) (justify left bottom) hide)
    )
    (property "Author" "Antmicro" (at 68.58 73.66 0)
      (effects (font (size 1.27 1.27) (thickness 0.15)) (justify left bottom) hide)
    )
    (property "License" "Apache-2.0" (at 68.58 76.2 0)
      (effects (font (size 1.27 1.27) (thickness 0.15)) (justify left bottom) hide)
    )
    (pin "1")
    (instances
      (project "d1600e-psu-breakout-board"
        (path ""
          (reference "#PWR014") (unit 1)
        )
      )
    )
  )

  (symbol (lib_id "antmicropower:GNDD") (at 45.72 66.04 0) (unit 1)
    (in_bom yes) (on_board yes) (dnp no) (fields_autoplaced)
    (property "Reference" "#PWR013" (at 45.72 72.39 0)
      (effects (font (size 1.27 1.27)) hide)
    )
    (property "Value" "GNDD" (at 45.72 69.85 0)
      (effects (font (size 1.27 1.27) (thickness 0.15)))
    )
    (property "Footprint" "" (at 60.96 76.2 0)
      (effects (font (size 1.27 1.27) (thickness 0.15)) (justify left bottom) hide)
    )
    (property "Datasheet" "" (at 60.96 78.74 0)
      (effects (font (size 1.27 1.27) (thickness 0.15)) (justify left bottom) hide)
    )
    (property "Author" "Antmicro" (at 60.96 73.66 0)
      (effects (font (size 1.27 1.27) (thickness 0.15)) (justify left bottom) hide)
    )
    (property "License" "Apache-2.0" (at 60.96 76.2 0)
      (effects (font (size 1.27 1.27) (thickness 0.15)) (justify left bottom) hide)
    )
    (pin "1")
    (instances
      (project "d1600e-psu-breakout-board"
        (path ""
          (reference "#PWR013") (unit 1)
        )
      )
    )
  )

  (symbol (lib_id "antmicropower:GNDD") (at 38.1 66.04 0) (unit 1)
    (in_bom yes) (on_board yes) (dnp no) (fields_autoplaced)
    (property "Reference" "#PWR010" (at 38.1 72.39 0)
      (effects (font (size 1.27 1.27)) hide)
    )
    (property "Value" "GNDD" (at 38.1 69.85 0)
      (effects (font (size 1.27 1.27) (thickness 0.15)))
    )
    (property "Footprint" "" (at 53.34 76.2 0)
      (effects (font (size 1.27 1.27) (thickness 0.15)) (justify left bottom) hide)
    )
    (property "Datasheet" "" (at 53.34 78.74 0)
      (effects (font (size 1.27 1.27) (thickness 0.15)) (justify left bottom) hide)
    )
    (property "Author" "Antmicro" (at 53.34 73.66 0)
      (effects (font (size 1.27 1.27) (thickness 0.15)) (justify left bottom) hide)
    )
    (property "License" "Apache-2.0" (at 53.34 76.2 0)
      (effects (font (size 1.27 1.27) (thickness 0.15)) (justify left bottom) hide)
    )
    (pin "1")
    (instances
      (project "d1600e-psu-breakout-board"
        (path ""
          (reference "#PWR010") (unit 1)
        )
      )
    )
  )

  (symbol (lib_id "antmicropower:GNDD") (at 30.48 66.04 0) (unit 1)
    (in_bom yes) (on_board yes) (dnp no) (fields_autoplaced)
    (property "Reference" "#PWR08" (at 30.48 72.39 0)
      (effects (font (size 1.27 1.27)) hide)
    )
    (property "Value" "GNDD" (at 30.48 69.85 0)
      (effects (font (size 1.27 1.27) (thickness 0.15)))
    )
    (property "Footprint" "" (at 45.72 76.2 0)
      (effects (font (size 1.27 1.27) (thickness 0.15)) (justify left bottom) hide)
    )
    (property "Datasheet" "" (at 45.72 78.74 0)
      (effects (font (size 1.27 1.27) (thickness 0.15)) (justify left bottom) hide)
    )
    (property "Author" "Antmicro" (at 45.72 73.66 0)
      (effects (font (size 1.27 1.27) (thickness 0.15)) (justify left bottom) hide)
    )
    (property "License" "Apache-2.0" (at 45.72 76.2 0)
      (effects (font (size 1.27 1.27) (thickness 0.15)) (justify left bottom) hide)
    )
    (pin "1")
    (instances
      (project "d1600e-psu-breakout-board"
        (path ""
          (reference "#PWR08") (unit 1)
        )
      )
    )
  )

  (symbol (lib_id "antmicropower:GNDD") (at 331.47 93.98 0) (unit 1)
    (in_bom yes) (on_board yes) (dnp no) (fields_autoplaced)
    (property "Reference" "#PWR039" (at 331.47 100.33 0)
      (effects (font (size 1.27 1.27)) hide)
    )
    (property "Value" "GNDD" (at 331.47 97.79 0)
      (effects (font (size 1.27 1.27) (thickness 0.15)))
    )
    (property "Footprint" "" (at 346.71 104.14 0)
      (effects (font (size 1.27 1.27) (thickness 0.15)) (justify left bottom) hide)
    )
    (property "Datasheet" "" (at 346.71 106.68 0)
      (effects (font (size 1.27 1.27) (thickness 0.15)) (justify left bottom) hide)
    )
    (property "Author" "Antmicro" (at 346.71 101.6 0)
      (effects (font (size 1.27 1.27) (thickness 0.15)) (justify left bottom) hide)
    )
    (property "License" "Apache-2.0" (at 346.71 104.14 0)
      (effects (font (size 1.27 1.27) (thickness 0.15)) (justify left bottom) hide)
    )
    (pin "1")
    (instances
      (project "d1600e-psu-breakout-board"
        (path ""
          (reference "#PWR039") (unit 1)
        )
      )
    )
  )

  (symbol (lib_id "antmicropower:GNDD") (at 322.58 93.98 0) (unit 1)
    (in_bom yes) (on_board yes) (dnp no) (fields_autoplaced)
    (property "Reference" "#PWR072" (at 322.58 100.33 0)
      (effects (font (size 1.27 1.27)) hide)
    )
    (property "Value" "GNDD" (at 322.58 97.79 0)
      (effects (font (size 1.27 1.27) (thickness 0.15)))
    )
    (property "Footprint" "" (at 337.82 104.14 0)
      (effects (font (size 1.27 1.27) (thickness 0.15)) (justify left bottom) hide)
    )
    (property "Datasheet" "" (at 337.82 106.68 0)
      (effects (font (size 1.27 1.27) (thickness 0.15)) (justify left bottom) hide)
    )
    (property "Author" "Antmicro" (at 337.82 101.6 0)
      (effects (font (size 1.27 1.27) (thickness 0.15)) (justify left bottom) hide)
    )
    (property "License" "Apache-2.0" (at 337.82 104.14 0)
      (effects (font (size 1.27 1.27) (thickness 0.15)) (justify left bottom) hide)
    )
    (pin "1")
    (instances
      (project "d1600e-psu-breakout-board"
        (path ""
          (reference "#PWR072") (unit 1)
        )
      )
    )
  )

  (symbol (lib_id "antmicropower:GNDD") (at 308.61 93.98 0) (unit 1)
    (in_bom yes) (on_board yes) (dnp no) (fields_autoplaced)
    (property "Reference" "#PWR078" (at 308.61 100.33 0)
      (effects (font (size 1.27 1.27)) hide)
    )
    (property "Value" "GNDD" (at 308.61 97.79 0)
      (effects (font (size 1.27 1.27) (thickness 0.15)))
    )
    (property "Footprint" "" (at 323.85 104.14 0)
      (effects (font (size 1.27 1.27) (thickness 0.15)) (justify left bottom) hide)
    )
    (property "Datasheet" "" (at 323.85 106.68 0)
      (effects (font (size 1.27 1.27) (thickness 0.15)) (justify left bottom) hide)
    )
    (property "Author" "Antmicro" (at 323.85 101.6 0)
      (effects (font (size 1.27 1.27) (thickness 0.15)) (justify left bottom) hide)
    )
    (property "License" "Apache-2.0" (at 323.85 104.14 0)
      (effects (font (size 1.27 1.27) (thickness 0.15)) (justify left bottom) hide)
    )
    (pin "1")
    (instances
      (project "d1600e-psu-breakout-board"
        (path ""
          (reference "#PWR078") (unit 1)
        )
      )
    )
  )

  (symbol (lib_id "antmicropower:GNDD") (at 289.56 34.29 0) (unit 1)
    (in_bom yes) (on_board yes) (dnp no) (fields_autoplaced)
    (property "Reference" "#PWR038" (at 289.56 40.64 0)
      (effects (font (size 1.27 1.27)) hide)
    )
    (property "Value" "GNDD" (at 289.56 38.1 0)
      (effects (font (size 1.27 1.27) (thickness 0.15)))
    )
    (property "Footprint" "" (at 304.8 44.45 0)
      (effects (font (size 1.27 1.27) (thickness 0.15)) (justify left bottom) hide)
    )
    (property "Datasheet" "" (at 304.8 46.99 0)
      (effects (font (size 1.27 1.27) (thickness 0.15)) (justify left bottom) hide)
    )
    (property "Author" "Antmicro" (at 304.8 41.91 0)
      (effects (font (size 1.27 1.27) (thickness 0.15)) (justify left bottom) hide)
    )
    (property "License" "Apache-2.0" (at 304.8 44.45 0)
      (effects (font (size 1.27 1.27) (thickness 0.15)) (justify left bottom) hide)
    )
    (pin "1")
    (instances
      (project "d1600e-psu-breakout-board"
        (path ""
          (reference "#PWR038") (unit 1)
        )
      )
    )
  )

  (symbol (lib_id "antmicropower:GNDD") (at 53.34 148.59 0) (unit 1)
    (in_bom yes) (on_board yes) (dnp no) (fields_autoplaced)
    (property "Reference" "#PWR02" (at 53.34 154.94 0)
      (effects (font (size 1.27 1.27)) hide)
    )
    (property "Value" "GNDD" (at 53.34 152.4 0)
      (effects (font (size 1.27 1.27) (thickness 0.15)))
    )
    (property "Footprint" "" (at 68.58 158.75 0)
      (effects (font (size 1.27 1.27) (thickness 0.15)) (justify left bottom) hide)
    )
    (property "Datasheet" "" (at 68.58 161.29 0)
      (effects (font (size 1.27 1.27) (thickness 0.15)) (justify left bottom) hide)
    )
    (property "Author" "Antmicro" (at 68.58 156.21 0)
      (effects (font (size 1.27 1.27) (thickness 0.15)) (justify left bottom) hide)
    )
    (property "License" "Apache-2.0" (at 68.58 158.75 0)
      (effects (font (size 1.27 1.27) (thickness 0.15)) (justify left bottom) hide)
    )
    (pin "1")
    (instances
      (project "d1600e-psu-breakout-board"
        (path ""
          (reference "#PWR02") (unit 1)
        )
      )
    )
  )

  (symbol (lib_id "antmicropower:GNDD") (at 63.5 148.59 0) (unit 1)
    (in_bom yes) (on_board yes) (dnp no) (fields_autoplaced)
    (property "Reference" "#PWR03" (at 63.5 154.94 0)
      (effects (font (size 1.27 1.27)) hide)
    )
    (property "Value" "GNDD" (at 63.5 152.4 0)
      (effects (font (size 1.27 1.27) (thickness 0.15)))
    )
    (property "Footprint" "" (at 78.74 158.75 0)
      (effects (font (size 1.27 1.27) (thickness 0.15)) (justify left bottom) hide)
    )
    (property "Datasheet" "" (at 78.74 161.29 0)
      (effects (font (size 1.27 1.27) (thickness 0.15)) (justify left bottom) hide)
    )
    (property "Author" "Antmicro" (at 78.74 156.21 0)
      (effects (font (size 1.27 1.27) (thickness 0.15)) (justify left bottom) hide)
    )
    (property "License" "Apache-2.0" (at 78.74 158.75 0)
      (effects (font (size 1.27 1.27) (thickness 0.15)) (justify left bottom) hide)
    )
    (pin "1")
    (instances
      (project "d1600e-psu-breakout-board"
        (path ""
          (reference "#PWR03") (unit 1)
        )
      )
    )
  )

  (symbol (lib_id "antmicropower:GNDD") (at 73.66 148.59 0) (unit 1)
    (in_bom yes) (on_board yes) (dnp no) (fields_autoplaced)
    (property "Reference" "#PWR05" (at 73.66 154.94 0)
      (effects (font (size 1.27 1.27)) hide)
    )
    (property "Value" "GNDD" (at 73.66 152.4 0)
      (effects (font (size 1.27 1.27) (thickness 0.15)))
    )
    (property "Footprint" "" (at 88.9 158.75 0)
      (effects (font (size 1.27 1.27) (thickness 0.15)) (justify left bottom) hide)
    )
    (property "Datasheet" "" (at 88.9 161.29 0)
      (effects (font (size 1.27 1.27) (thickness 0.15)) (justify left bottom) hide)
    )
    (property "Author" "Antmicro" (at 88.9 156.21 0)
      (effects (font (size 1.27 1.27) (thickness 0.15)) (justify left bottom) hide)
    )
    (property "License" "Apache-2.0" (at 88.9 158.75 0)
      (effects (font (size 1.27 1.27) (thickness 0.15)) (justify left bottom) hide)
    )
    (pin "1")
    (instances
      (project "d1600e-psu-breakout-board"
        (path ""
          (reference "#PWR05") (unit 1)
        )
      )
    )
  )

  (symbol (lib_id "antmicropower:GNDD") (at 276.86 224.79 0) (unit 1)
    (in_bom yes) (on_board yes) (dnp no) (fields_autoplaced)
    (property "Reference" "#PWR037" (at 276.86 231.14 0)
      (effects (font (size 1.27 1.27)) hide)
    )
    (property "Value" "GNDD" (at 276.86 228.6 0)
      (effects (font (size 1.27 1.27) (thickness 0.15)))
    )
    (property "Footprint" "" (at 292.1 234.95 0)
      (effects (font (size 1.27 1.27) (thickness 0.15)) (justify left bottom) hide)
    )
    (property "Datasheet" "" (at 292.1 237.49 0)
      (effects (font (size 1.27 1.27) (thickness 0.15)) (justify left bottom) hide)
    )
    (property "Author" "Antmicro" (at 292.1 232.41 0)
      (effects (font (size 1.27 1.27) (thickness 0.15)) (justify left bottom) hide)
    )
    (property "License" "Apache-2.0" (at 292.1 234.95 0)
      (effects (font (size 1.27 1.27) (thickness 0.15)) (justify left bottom) hide)
    )
    (pin "1")
    (instances
      (project "d1600e-psu-breakout-board"
        (path ""
          (reference "#PWR037") (unit 1)
        )
      )
    )
  )

  (symbol (lib_id "antmicroTestPoints:TP_1mm_SMD") (at 354.33 222.25 0) (unit 1)
    (in_bom no) (on_board yes) (dnp no) (fields_autoplaced)
    (property "Reference" "SCL_FTDI1" (at 359.41 222.25 0)
      (effects (font (size 1.27 1.27)) (justify left))
    )
    (property "Value" "TP_1mm_SMD" (at 369.57 229.87 0)
      (effects (font (size 1.27 1.27) (thickness 0.15)) (justify left bottom) hide)
    )
    (property "Footprint" "antmicro-footprints:TP_SMD_1mm" (at 369.57 232.41 0)
      (effects (font (size 1.27 1.27) (thickness 0.15)) (justify left bottom) hide)
    )
    (property "Datasheet" "" (at 372.11 234.95 0)
      (effects (font (size 1.27 1.27) (thickness 0.15)) (justify left bottom) hide)
    )
    (property "MPN" "" (at 354.33 222.25 0)
      (effects (font (size 1.27 1.27)) hide)
    )
    (property "Manufacturer" "" (at 354.33 222.25 0)
      (effects (font (size 1.27 1.27)) hide)
    )
    (property "Author" "Antmicro" (at 369.57 237.49 0)
      (effects (font (size 1.27 1.27) (thickness 0.15)) (justify left bottom) hide)
    )
    (property "License" "Apache-2.0" (at 369.57 240.03 0)
      (effects (font (size 1.27 1.27) (thickness 0.15)) (justify left bottom) hide)
    )
    (pin "1")
    (instances
      (project "d1600e-psu-breakout-board"
        (path ""
          (reference "SCL_FTDI1") (unit 1)
        )
      )
    )
  )

  (symbol (lib_id "antmicroTestPoints:TP_1mm_SMD") (at 354.33 226.06 0) (unit 1)
    (in_bom no) (on_board yes) (dnp no) (fields_autoplaced)
    (property "Reference" "SDA_FTDI1" (at 359.41 226.06 0)
      (effects (font (size 1.27 1.27)) (justify left))
    )
    (property "Value" "TP_1mm_SMD" (at 369.57 233.68 0)
      (effects (font (size 1.27 1.27) (thickness 0.15)) (justify left bottom) hide)
    )
    (property "Footprint" "antmicro-footprints:TP_SMD_1mm" (at 369.57 236.22 0)
      (effects (font (size 1.27 1.27) (thickness 0.15)) (justify left bottom) hide)
    )
    (property "Datasheet" "" (at 372.11 238.76 0)
      (effects (font (size 1.27 1.27) (thickness 0.15)) (justify left bottom) hide)
    )
    (property "MPN" "" (at 354.33 226.06 0)
      (effects (font (size 1.27 1.27)) hide)
    )
    (property "Manufacturer" "" (at 354.33 226.06 0)
      (effects (font (size 1.27 1.27)) hide)
    )
    (property "Author" "Antmicro" (at 369.57 241.3 0)
      (effects (font (size 1.27 1.27) (thickness 0.15)) (justify left bottom) hide)
    )
    (property "License" "Apache-2.0" (at 369.57 243.84 0)
      (effects (font (size 1.27 1.27) (thickness 0.15)) (justify left bottom) hide)
    )
    (pin "1")
    (instances
      (project "d1600e-psu-breakout-board"
        (path ""
          (reference "SDA_FTDI1") (unit 1)
        )
      )
    )
  )

  (symbol (lib_id "antmicroTestPoints:TP_1mm_SMD") (at 354.33 203.2 0) (unit 1)
    (in_bom no) (on_board yes) (dnp no) (fields_autoplaced)
    (property "Reference" "3V3_USB1" (at 359.41 203.2 0)
      (effects (font (size 1.27 1.27)) (justify left))
    )
    (property "Value" "TP_1mm_SMD" (at 369.57 210.82 0)
      (effects (font (size 1.27 1.27) (thickness 0.15)) (justify left bottom) hide)
    )
    (property "Footprint" "antmicro-footprints:TP_SMD_1mm" (at 369.57 213.36 0)
      (effects (font (size 1.27 1.27) (thickness 0.15)) (justify left bottom) hide)
    )
    (property "Datasheet" "" (at 372.11 215.9 0)
      (effects (font (size 1.27 1.27) (thickness 0.15)) (justify left bottom) hide)
    )
    (property "MPN" "" (at 354.33 203.2 0)
      (effects (font (size 1.27 1.27)) hide)
    )
    (property "Manufacturer" "" (at 354.33 203.2 0)
      (effects (font (size 1.27 1.27)) hide)
    )
    (property "Author" "Antmicro" (at 369.57 218.44 0)
      (effects (font (size 1.27 1.27) (thickness 0.15)) (justify left bottom) hide)
    )
    (property "License" "Apache-2.0" (at 369.57 220.98 0)
      (effects (font (size 1.27 1.27) (thickness 0.15)) (justify left bottom) hide)
    )
    (pin "1")
    (instances
      (project "d1600e-psu-breakout-board"
        (path ""
          (reference "3V3_USB1") (unit 1)
        )
      )
    )
  )

  (symbol (lib_id "antmicropower:GND") (at 210.82 255.27 0) (unit 1)
    (in_bom yes) (on_board yes) (dnp no)
    (property "Reference" "#PWR036" (at 210.82 261.62 0)
      (effects (font (size 1.27 1.27)) hide)
    )
    (property "Value" "GND" (at 210.82 259.08 0)
      (effects (font (size 1.27 1.27) (thickness 0.15)))
    )
    (property "Footprint" "" (at 219.71 262.89 0)
      (effects (font (size 1.27 1.27) (thickness 0.15)) (justify left bottom) hide)
    )
    (property "Datasheet" "" (at 219.71 267.97 0)
      (effects (font (size 1.27 1.27) (thickness 0.15)) (justify left bottom) hide)
    )
    (property "Author" "Antmicro" (at 219.71 262.89 0)
      (effects (font (size 1.27 1.27) (thickness 0.15)) (justify left bottom) hide)
    )
    (property "License" "Apache-2.0" (at 219.71 265.43 0)
      (effects (font (size 1.27 1.27) (thickness 0.15)) (justify left bottom) hide)
    )
    (pin "1")
    (instances
      (project "d1600e-psu-breakout-board"
        (path ""
          (reference "#PWR036") (unit 1)
        )
      )
    )
  )

  (symbol (lib_id "antmicropower:GNDD") (at 196.85 255.27 0) (unit 1)
    (in_bom yes) (on_board yes) (dnp no) (fields_autoplaced)
    (property "Reference" "#PWR029" (at 196.85 261.62 0)
      (effects (font (size 1.27 1.27)) hide)
    )
    (property "Value" "GNDD" (at 196.85 259.08 0)
      (effects (font (size 1.27 1.27) (thickness 0.15)))
    )
    (property "Footprint" "" (at 212.09 265.43 0)
      (effects (font (size 1.27 1.27) (thickness 0.15)) (justify left bottom) hide)
    )
    (property "Datasheet" "" (at 212.09 267.97 0)
      (effects (font (size 1.27 1.27) (thickness 0.15)) (justify left bottom) hide)
    )
    (property "Author" "Antmicro" (at 212.09 262.89 0)
      (effects (font (size 1.27 1.27) (thickness 0.15)) (justify left bottom) hide)
    )
    (property "License" "Apache-2.0" (at 212.09 265.43 0)
      (effects (font (size 1.27 1.27) (thickness 0.15)) (justify left bottom) hide)
    )
    (pin "1")
    (instances
      (project "d1600e-psu-breakout-board"
        (path ""
          (reference "#PWR029") (unit 1)
        )
      )
    )
  )

  (symbol (lib_name "R_0R_0603_3") (lib_id "antmicroResistors0603:R_0R_0603") (at 200.66 226.06 0) (unit 1)
    (in_bom no) (on_board yes) (dnp yes)
    (property "Reference" "R38" (at 203.2 220.98 0)
      (effects (font (size 1.27 1.27)))
    )
    (property "Value" "R_0R_0603" (at 220.98 238.76 0)
      (effects (font (size 1.27 1.27) (thickness 0.15)) (justify left bottom) hide)
    )
    (property "Footprint" "antmicro-footprints:R_0603_1608Metric" (at 220.98 241.3 0)
      (effects (font (size 1.27 1.27) (thickness 0.15)) (justify left bottom) hide)
    )
    (property "Datasheet" "https://www.bourns.com/docs/product-datasheets/cr.pdf?sfvrsn=574d41f6_14" (at 220.98 243.84 0)
      (effects (font (size 1.27 1.27) (thickness 0.15)) (justify left bottom) hide)
    )
    (property "Manufacturer" "Bourns" (at 220.98 248.92 0)
      (effects (font (size 1.27 1.27) (thickness 0.15)) (justify left bottom) hide)
    )
    (property "MPN" "CR0603-J/-000ELF" (at 220.98 246.38 0)
      (effects (font (size 1.27 1.27) (thickness 0.15)) (justify left bottom) hide)
    )
    (property "Val" "0R" (at 203.2 223.52 0)
      (effects (font (size 1.27 1.27) (thickness 0.15)))
    )
    (property "DNP" "DNP" (at 203.2 228.6 0)
      (effects (font (size 1.27 1.27)))
    )
    (property "License" "Apache-2.0" (at 220.98 251.46 0)
      (effects (font (size 1.27 1.27) (thickness 0.15)) (justify left bottom) hide)
    )
    (property "Author" "Antmicro" (at 220.98 254 0)
      (effects (font (size 1.27 1.27) (thickness 0.15)) (justify left bottom) hide)
    )
    (property "Tolerance" "~" (at 220.98 236.22 0)
      (effects (font (size 1.27 1.27)) (justify left bottom) hide)
    )
    (property "Current" "1A" (at 220.98 256.54 0)
      (effects (font (size 1.27 1.27) (thickness 0.15)) (justify left bottom) hide)
    )
    (pin "1")
    (pin "2")
    (instances
      (project "d1600e-psu-breakout-board"
        (path ""
          (reference "R38") (unit 1)
        )
      )
    )
  )

  (symbol (lib_id "antmicroTestPoints:TP_1mm_SMD") (at 354.33 214.63 0) (unit 1)
    (in_bom no) (on_board yes) (dnp no) (fields_autoplaced)
    (property "Reference" "SCL1" (at 359.41 214.63 0)
      (effects (font (size 1.27 1.27)) (justify left))
    )
    (property "Value" "TP_1mm_SMD" (at 369.57 222.25 0)
      (effects (font (size 1.27 1.27) (thickness 0.15)) (justify left bottom) hide)
    )
    (property "Footprint" "antmicro-footprints:TP_SMD_1mm" (at 369.57 224.79 0)
      (effects (font (size 1.27 1.27) (thickness 0.15)) (justify left bottom) hide)
    )
    (property "Datasheet" "" (at 372.11 227.33 0)
      (effects (font (size 1.27 1.27) (thickness 0.15)) (justify left bottom) hide)
    )
    (property "MPN" "" (at 354.33 214.63 0)
      (effects (font (size 1.27 1.27)) hide)
    )
    (property "Manufacturer" "" (at 354.33 214.63 0)
      (effects (font (size 1.27 1.27)) hide)
    )
    (property "Author" "Antmicro" (at 369.57 229.87 0)
      (effects (font (size 1.27 1.27) (thickness 0.15)) (justify left bottom) hide)
    )
    (property "License" "Apache-2.0" (at 369.57 232.41 0)
      (effects (font (size 1.27 1.27) (thickness 0.15)) (justify left bottom) hide)
    )
    (pin "1")
    (instances
      (project "d1600e-psu-breakout-board"
        (path ""
          (reference "SCL1") (unit 1)
        )
      )
    )
  )

  (symbol (lib_name "R_0R_0603_4") (lib_id "antmicroResistors0603:R_0R_0603") (at 200.66 240.03 0) (unit 1)
    (in_bom no) (on_board yes) (dnp yes)
    (property "Reference" "R39" (at 203.2 234.95 0)
      (effects (font (size 1.27 1.27)))
    )
    (property "Value" "R_0R_0603" (at 220.98 252.73 0)
      (effects (font (size 1.27 1.27) (thickness 0.15)) (justify left bottom) hide)
    )
    (property "Footprint" "antmicro-footprints:R_0603_1608Metric" (at 220.98 255.27 0)
      (effects (font (size 1.27 1.27) (thickness 0.15)) (justify left bottom) hide)
    )
    (property "Datasheet" "https://www.bourns.com/docs/product-datasheets/cr.pdf?sfvrsn=574d41f6_14" (at 220.98 257.81 0)
      (effects (font (size 1.27 1.27) (thickness 0.15)) (justify left bottom) hide)
    )
    (property "Manufacturer" "Bourns" (at 220.98 262.89 0)
      (effects (font (size 1.27 1.27) (thickness 0.15)) (justify left bottom) hide)
    )
    (property "MPN" "CR0603-J/-000ELF" (at 220.98 260.35 0)
      (effects (font (size 1.27 1.27) (thickness 0.15)) (justify left bottom) hide)
    )
    (property "Val" "0R" (at 203.2 237.49 0)
      (effects (font (size 1.27 1.27) (thickness 0.15)))
    )
    (property "DNP" "DNP" (at 203.2 242.57 0)
      (effects (font (size 1.27 1.27)))
    )
    (property "License" "Apache-2.0" (at 220.98 265.43 0)
      (effects (font (size 1.27 1.27) (thickness 0.15)) (justify left bottom) hide)
    )
    (property "Author" "Antmicro" (at 220.98 267.97 0)
      (effects (font (size 1.27 1.27) (thickness 0.15)) (justify left bottom) hide)
    )
    (property "Tolerance" "~" (at 220.98 250.19 0)
      (effects (font (size 1.27 1.27)) (justify left bottom) hide)
    )
    (property "Current" "1A" (at 220.98 270.51 0)
      (effects (font (size 1.27 1.27) (thickness 0.15)) (justify left bottom) hide)
    )
    (pin "1")
    (pin "2")
    (instances
      (project "d1600e-psu-breakout-board"
        (path ""
          (reference "R39") (unit 1)
        )
      )
    )
  )

  (symbol (lib_name "R_0R_0603_5") (lib_id "antmicroResistors0603:R_0R_0603") (at 200.66 254 0) (unit 1)
    (in_bom no) (on_board yes) (dnp yes)
    (property "Reference" "R42" (at 203.2 248.92 0)
      (effects (font (size 1.27 1.27)))
    )
    (property "Value" "R_0R_0603" (at 220.98 266.7 0)
      (effects (font (size 1.27 1.27) (thickness 0.15)) (justify left bottom) hide)
    )
    (property "Footprint" "antmicro-footprints:R_0603_1608Metric" (at 220.98 269.24 0)
      (effects (font (size 1.27 1.27) (thickness 0.15)) (justify left bottom) hide)
    )
    (property "Datasheet" "https://www.bourns.com/docs/product-datasheets/cr.pdf?sfvrsn=574d41f6_14" (at 220.98 271.78 0)
      (effects (font (size 1.27 1.27) (thickness 0.15)) (justify left bottom) hide)
    )
    (property "Manufacturer" "Bourns" (at 220.98 276.86 0)
      (effects (font (size 1.27 1.27) (thickness 0.15)) (justify left bottom) hide)
    )
    (property "MPN" "CR0603-J/-000ELF" (at 220.98 274.32 0)
      (effects (font (size 1.27 1.27) (thickness 0.15)) (justify left bottom) hide)
    )
    (property "Val" "0R" (at 203.2 251.46 0)
      (effects (font (size 1.27 1.27) (thickness 0.15)))
    )
    (property "DNP" "DNP" (at 203.2 256.54 0)
      (effects (font (size 1.27 1.27)))
    )
    (property "License" "Apache-2.0" (at 220.98 279.4 0)
      (effects (font (size 1.27 1.27) (thickness 0.15)) (justify left bottom) hide)
    )
    (property "Author" "Antmicro" (at 220.98 281.94 0)
      (effects (font (size 1.27 1.27) (thickness 0.15)) (justify left bottom) hide)
    )
    (property "Tolerance" "~" (at 220.98 264.16 0)
      (effects (font (size 1.27 1.27)) (justify left bottom) hide)
    )
    (property "Current" "1A" (at 220.98 284.48 0)
      (effects (font (size 1.27 1.27) (thickness 0.15)) (justify left bottom) hide)
    )
    (pin "1")
    (pin "2")
    (instances
      (project "d1600e-psu-breakout-board"
        (path ""
          (reference "R42") (unit 1)
        )
      )
    )
  )

  (symbol (lib_id "antmicroPMICVoltageRegulatorsLinear:NCP163ASN330T1G") (at 306.07 151.13 0) (unit 1)
    (in_bom yes) (on_board yes) (dnp no) (fields_autoplaced)
    (property "Reference" "U3" (at 316.23 143.51 0)
      (effects (font (size 1.27 1.27)))
    )
    (property "Value" "NCP163ASN330T1G" (at 341.63 158.75 0)
      (effects (font (size 1.27 1.27) (thickness 0.15)) (justify left bottom) hide)
    )
    (property "Footprint" "antmicro-footprints:SOT-23-5" (at 341.63 161.29 0)
      (effects (font (size 1.27 1.27) (thickness 0.15)) (justify left bottom) hide)
    )
    (property "Datasheet" "https://mouser.com/datasheet/2/308/1/NCP163_D-2317108.pdf" (at 341.63 163.83 0)
      (effects (font (size 1.27 1.27) (thickness 0.15)) (justify left bottom) hide)
    )
    (property "MPN" "NCP163ASN330T1G" (at 316.23 146.05 0)
      (effects (font (size 1.27 1.27) (thickness 0.15)))
    )
    (property "Manufacturer" "ON Semiconductor" (at 341.63 166.37 0)
      (effects (font (size 1.27 1.27) (thickness 0.15)) (justify left bottom) hide)
    )
    (property "Author" "Antmicro" (at 341.63 168.91 0)
      (effects (font (size 1.27 1.27) (thickness 0.15)) (justify left bottom) hide)
    )
    (property "License" "Apache-2.0" (at 341.63 171.45 0)
      (effects (font (size 1.27 1.27) (thickness 0.15)) (justify left bottom) hide)
    )
    (pin "1")
    (pin "2")
    (pin "3")
    (pin "5")
    (pin "4")
    (instances
      (project "d1600e-psu-breakout-board"
        (path ""
          (reference "U3") (unit 1)
        )
      )
    )
  )

  (symbol (lib_id "antmicropower:GNDD") (at 295.91 161.29 0) (unit 1)
    (in_bom yes) (on_board yes) (dnp no) (fields_autoplaced)
    (property "Reference" "#PWR040" (at 295.91 167.64 0)
      (effects (font (size 1.27 1.27)) hide)
    )
    (property "Value" "GNDD" (at 295.91 165.1 0)
      (effects (font (size 1.27 1.27) (thickness 0.15)))
    )
    (property "Footprint" "" (at 311.15 171.45 0)
      (effects (font (size 1.27 1.27) (thickness 0.15)) (justify left bottom) hide)
    )
    (property "Datasheet" "" (at 311.15 173.99 0)
      (effects (font (size 1.27 1.27) (thickness 0.15)) (justify left bottom) hide)
    )
    (property "Author" "Antmicro" (at 311.15 168.91 0)
      (effects (font (size 1.27 1.27) (thickness 0.15)) (justify left bottom) hide)
    )
    (property "License" "Apache-2.0" (at 311.15 171.45 0)
      (effects (font (size 1.27 1.27) (thickness 0.15)) (justify left bottom) hide)
    )
    (pin "1")
    (instances
      (project "d1600e-psu-breakout-board"
        (path ""
          (reference "#PWR040") (unit 1)
        )
      )
    )
  )

  (symbol (lib_id "antmicroTestPoints:TP_1mm_SMD") (at 354.33 218.44 0) (unit 1)
    (in_bom no) (on_board yes) (dnp no) (fields_autoplaced)
    (property "Reference" "SDA1" (at 359.41 218.44 0)
      (effects (font (size 1.27 1.27)) (justify left))
    )
    (property "Value" "TP_1mm_SMD" (at 369.57 226.06 0)
      (effects (font (size 1.27 1.27) (thickness 0.15)) (justify left bottom) hide)
    )
    (property "Footprint" "antmicro-footprints:TP_SMD_1mm" (at 369.57 228.6 0)
      (effects (font (size 1.27 1.27) (thickness 0.15)) (justify left bottom) hide)
    )
    (property "Datasheet" "" (at 372.11 231.14 0)
      (effects (font (size 1.27 1.27) (thickness 0.15)) (justify left bottom) hide)
    )
    (property "MPN" "" (at 354.33 218.44 0)
      (effects (font (size 1.27 1.27)) hide)
    )
    (property "Manufacturer" "" (at 354.33 218.44 0)
      (effects (font (size 1.27 1.27)) hide)
    )
    (property "Author" "Antmicro" (at 369.57 233.68 0)
      (effects (font (size 1.27 1.27) (thickness 0.15)) (justify left bottom) hide)
    )
    (property "License" "Apache-2.0" (at 369.57 236.22 0)
      (effects (font (size 1.27 1.27) (thickness 0.15)) (justify left bottom) hide)
    )
    (pin "1")
    (instances
      (project "d1600e-psu-breakout-board"
        (path ""
          (reference "SDA1") (unit 1)
        )
      )
    )
  )

  (symbol (lib_id "antmicropower:GNDD") (at 328.93 161.29 0) (unit 1)
    (in_bom yes) (on_board yes) (dnp no) (fields_autoplaced)
    (property "Reference" "#PWR076" (at 328.93 167.64 0)
      (effects (font (size 1.27 1.27)) hide)
    )
    (property "Value" "GNDD" (at 328.93 165.1 0)
      (effects (font (size 1.27 1.27) (thickness 0.15)))
    )
    (property "Footprint" "" (at 344.17 171.45 0)
      (effects (font (size 1.27 1.27) (thickness 0.15)) (justify left bottom) hide)
    )
    (property "Datasheet" "" (at 344.17 173.99 0)
      (effects (font (size 1.27 1.27) (thickness 0.15)) (justify left bottom) hide)
    )
    (property "Author" "Antmicro" (at 344.17 168.91 0)
      (effects (font (size 1.27 1.27) (thickness 0.15)) (justify left bottom) hide)
    )
    (property "License" "Apache-2.0" (at 344.17 171.45 0)
      (effects (font (size 1.27 1.27) (thickness 0.15)) (justify left bottom) hide)
    )
    (pin "1")
    (instances
      (project "d1600e-psu-breakout-board"
        (path ""
          (reference "#PWR076") (unit 1)
        )
      )
    )
  )

  (symbol (lib_id "antmicropower:GNDD") (at 335.28 161.29 0) (unit 1)
    (in_bom yes) (on_board yes) (dnp no) (fields_autoplaced)
    (property "Reference" "#PWR077" (at 335.28 167.64 0)
      (effects (font (size 1.27 1.27)) hide)
    )
    (property "Value" "GNDD" (at 335.28 165.1 0)
      (effects (font (size 1.27 1.27) (thickness 0.15)))
    )
    (property "Footprint" "" (at 350.52 171.45 0)
      (effects (font (size 1.27 1.27) (thickness 0.15)) (justify left bottom) hide)
    )
    (property "Datasheet" "" (at 350.52 173.99 0)
      (effects (font (size 1.27 1.27) (thickness 0.15)) (justify left bottom) hide)
    )
    (property "Author" "Antmicro" (at 350.52 168.91 0)
      (effects (font (size 1.27 1.27) (thickness 0.15)) (justify left bottom) hide)
    )
    (property "License" "Apache-2.0" (at 350.52 171.45 0)
      (effects (font (size 1.27 1.27) (thickness 0.15)) (justify left bottom) hide)
    )
    (pin "1")
    (instances
      (project "d1600e-psu-breakout-board"
        (path ""
          (reference "#PWR077") (unit 1)
        )
      )
    )
  )

  (symbol (lib_name "FB_600Z_0.5A_Murata-BLM18AG_0603_2") (lib_id "antmicroFerriteBeadsandChips:FB_600Z_0.5A_Murata-BLM18AG_0603") (at 46.99 86.36 0) (mirror y) (unit 1)
    (in_bom yes) (on_board yes) (dnp no)
    (property "Reference" "FB1" (at 44.45 90.17 0)
      (effects (font (size 1.27 1.27)))
    )
    (property "Value" "FB_600Z_0.5A_Murata-BLM18AG_0603" (at 31.75 88.9 0)
      (effects (font (size 1.27 1.27) (thickness 0.15)) (justify left bottom) hide)
    )
    (property "Footprint" "antmicro-footprints:FB_0603_1608Metric" (at 31.75 93.98 0)
      (effects (font (size 1.27 1.27) (thickness 0.15)) (justify left bottom) hide)
    )
    (property "Datasheet" "https://www.murata.com/en-us/products/productdata/8796738650142/ENFA0003.pdf" (at 31.75 96.52 0)
      (effects (font (size 1.27 1.27) (thickness 0.15)) (justify left bottom) hide)
    )
    (property "MPN" "BLM18AG601SN1D" (at 31.75 99.06 0)
      (effects (font (size 1.27 1.27) (thickness 0.15)) (justify left bottom) hide)
    )
    (property "Manufacturer" "Murata" (at 31.75 101.6 0)
      (effects (font (size 1.27 1.27) (thickness 0.15)) (justify left bottom) hide)
    )
    (property "Val" "600Z/0.5A" (at 44.4881 92.71 0)
      (effects (font (size 1.27 1.27)))
    )
    (property "Current" "" (at 26.67 109.22 0)
      (effects (font (size 1.27 1.27) (thickness 0.15)) (justify left bottom) hide)
    )
    (property "Author" "Antmicro" (at 31.75 104.14 0)
      (effects (font (size 1.27 1.27) (thickness 0.15)) (justify left bottom) hide)
    )
    (property "License" "Apache-2.0" (at 31.75 106.68 0)
      (effects (font (size 1.27 1.27) (thickness 0.15)) (justify left bottom) hide)
    )
    (pin "1")
    (pin "2")
    (instances
      (project "d1600e-psu-breakout-board"
        (path ""
          (reference "FB1") (unit 1)
        )
      )
    )
  )

  (symbol (lib_name "C_18p_0402_1") (lib_id "antmicroCapacitors0402:C_18p_0402") (at 53.34 142.24 90) (unit 1)
    (in_bom yes) (on_board yes) (dnp no)
    (property "Reference" "C1" (at 53.975 137.795 90)
      (effects (font (size 1.27 1.27)) (justify right))
    )
    (property "Value" "C_18p_0402" (at 63.5 121.92 0)
      (effects (font (size 1.27 1.27) (thickness 0.15)) (justify left bottom) hide)
    )
    (property "Footprint" "antmicro-footprints:C_0402_1005Metric" (at 66.04 121.92 0)
      (effects (font (size 1.27 1.27) (thickness 0.15)) (justify left bottom) hide)
    )
    (property "Datasheet" "https://product.samsungsem.com/mlcc/CL05C180JB51PN.do" (at 68.58 121.92 0)
      (effects (font (size 1.27 1.27) (thickness 0.15)) (justify left bottom) hide)
    )
    (property "Manufacturer" "Samsung Electro-Mechanics" (at 73.66 121.92 0)
      (effects (font (size 1.27 1.27) (thickness 0.15)) (justify left bottom) hide)
    )
    (property "MPN" "CL05C180JB51PNC" (at 71.12 121.92 0)
      (effects (font (size 1.27 1.27) (thickness 0.15)) (justify left bottom) hide)
    )
    (property "Val" "18p" (at 53.975 141.605 90)
      (effects (font (size 1.27 1.27) (thickness 0.15)) (justify right))
    )
    (property "License" "Apache-2.0" (at 76.2 121.92 0)
      (effects (font (size 1.27 1.27) (thickness 0.15)) (justify left bottom) hide)
    )
    (property "Author" "Antmicro" (at 78.74 121.92 0)
      (effects (font (size 1.27 1.27) (thickness 0.15)) (justify left bottom) hide)
    )
    (property "Voltage" "" (at 81.28 121.92 0)
      (effects (font (size 1.27 1.27)) (justify left bottom) hide)
    )
    (property "Dielectric" "" (at 83.82 121.92 0)
      (effects (font (size 1.27 1.27)) (justify left bottom) hide)
    )
    (pin "1")
    (pin "2")
    (instances
      (project "d1600e-psu-breakout-board"
        (path ""
          (reference "C1") (unit 1)
        )
      )
    )
  )

  (symbol (lib_name "C_4u7_0402_3") (lib_id "antmicroCapacitors0402:C_4u7_0402") (at 63.5 69.85 270) (mirror x) (unit 1)
    (in_bom yes) (on_board yes) (dnp no)
    (property "Reference" "C13" (at 67.945 65.405 90)
      (effects (font (size 1.27 1.27)) (justify right))
    )
    (property "Value" "C_4u7_0402" (at 53.34 49.53 0)
      (effects (font (size 1.27 1.27) (thickness 0.15)) (justify left bottom) hide)
    )
    (property "Footprint" "antmicro-footprints:C_0402_1005Metric" (at 50.8 49.53 0)
      (effects (font (size 1.27 1.27) (thickness 0.15)) (justify left bottom) hide)
    )
    (property "Datasheet" "https://www.murata.com/products/productdetail?partno=GRM155R61A475MEAA%23" (at 48.26 49.53 0)
      (effects (font (size 1.27 1.27) (thickness 0.15)) (justify left bottom) hide)
    )
    (property "Manufacturer" "Murata" (at 43.18 49.53 0)
      (effects (font (size 1.27 1.27) (thickness 0.15)) (justify left bottom) hide)
    )
    (property "MPN" "GRM155R61A475MEAAD" (at 45.72 49.53 0)
      (effects (font (size 1.27 1.27) (thickness 0.15)) (justify left bottom) hide)
    )
    (property "Val" "4u7" (at 67.945 69.215 90)
      (effects (font (size 1.27 1.27) (thickness 0.15)) (justify right))
    )
    (property "License" "Apache-2.0" (at 40.64 49.53 0)
      (effects (font (size 1.27 1.27) (thickness 0.15)) (justify left bottom) hide)
    )
    (property "Author" "Antmicro" (at 38.1 49.53 0)
      (effects (font (size 1.27 1.27) (thickness 0.15)) (justify left bottom) hide)
    )
    (property "Voltage" "" (at 35.56 49.53 0)
      (effects (font (size 1.27 1.27)) (justify left bottom) hide)
    )
    (property "Dielectric" "" (at 33.02 49.53 0)
      (effects (font (size 1.27 1.27)) (justify left bottom) hide)
    )
    (pin "1")
    (pin "2")
    (instances
      (project "d1600e-psu-breakout-board"
        (path ""
          (reference "C13") (unit 1)
        )
      )
    )
  )

  (symbol (lib_id "antmicropower:GNDD") (at 72.39 97.79 0) (mirror y) (unit 1)
    (in_bom yes) (on_board yes) (dnp no) (fields_autoplaced)
    (property "Reference" "#PWR0118" (at 72.39 104.14 0)
      (effects (font (size 1.27 1.27)) hide)
    )
    (property "Value" "GNDD" (at 72.39 101.6 0)
      (effects (font (size 1.27 1.27) (thickness 0.15)))
    )
    (property "Footprint" "" (at 57.15 107.95 0)
      (effects (font (size 1.27 1.27) (thickness 0.15)) (justify left bottom) hide)
    )
    (property "Datasheet" "" (at 57.15 110.49 0)
      (effects (font (size 1.27 1.27) (thickness 0.15)) (justify left bottom) hide)
    )
    (property "Author" "Antmicro" (at 57.15 105.41 0)
      (effects (font (size 1.27 1.27) (thickness 0.15)) (justify left bottom) hide)
    )
    (property "License" "Apache-2.0" (at 57.15 107.95 0)
      (effects (font (size 1.27 1.27) (thickness 0.15)) (justify left bottom) hide)
    )
    (pin "1")
    (instances
      (project "d1600e-psu-breakout-board"
        (path ""
          (reference "#PWR0118") (unit 1)
        )
      )
    )
  )

  (symbol (lib_id "antmicropower:GND") (at 186.69 123.19 0) (unit 1)
    (in_bom yes) (on_board yes) (dnp no)
    (property "Reference" "#PWR022" (at 186.69 129.54 0)
      (effects (font (size 1.27 1.27)) hide)
    )
    (property "Value" "GND" (at 186.69 127 0)
      (effects (font (size 1.27 1.27) (thickness 0.15)))
    )
    (property "Footprint" "" (at 195.58 130.81 0)
      (effects (font (size 1.27 1.27) (thickness 0.15)) (justify left bottom) hide)
    )
    (property "Datasheet" "" (at 195.58 135.89 0)
      (effects (font (size 1.27 1.27) (thickness 0.15)) (justify left bottom) hide)
    )
    (property "Author" "Antmicro" (at 195.58 130.81 0)
      (effects (font (size 1.27 1.27) (thickness 0.15)) (justify left bottom) hide)
    )
    (property "License" "Apache-2.0" (at 195.58 133.35 0)
      (effects (font (size 1.27 1.27) (thickness 0.15)) (justify left bottom) hide)
    )
    (pin "1")
    (instances
      (project "d1600e-psu-breakout-board"
        (path ""
          (reference "#PWR022") (unit 1)
        )
      )
    )
  )

  (symbol (lib_id "antmicroResistors0402:R_1k_0402") (at 87.63 110.49 0) (unit 1)
    (in_bom yes) (on_board yes) (dnp no)
    (property "Reference" "R1" (at 90.17 105.41 0)
      (effects (font (size 1.27 1.27)))
    )
    (property "Value" "R_1k_0402" (at 107.95 123.19 0)
      (effects (font (size 1.27 1.27) (thickness 0.15)) (justify left bottom) hide)
    )
    (property "Footprint" "antmicro-footprints:R_0402_1005Metric" (at 107.95 125.73 0)
      (effects (font (size 1.27 1.27) (thickness 0.15)) (justify left bottom) hide)
    )
    (property "Datasheet" "https://www.bourns.com/docs/product-datasheets/cr.pdf" (at 107.95 128.27 0)
      (effects (font (size 1.27 1.27) (thickness 0.15)) (justify left bottom) hide)
    )
    (property "Manufacturer" "Bourns" (at 107.95 133.35 0)
      (effects (font (size 1.27 1.27) (thickness 0.15)) (justify left bottom) hide)
    )
    (property "MPN" "CR0402-FX-1001GLF" (at 107.95 130.81 0)
      (effects (font (size 1.27 1.27) (thickness 0.15)) (justify left bottom) hide)
    )
    (property "Val" "1k" (at 90.17 107.95 0)
      (effects (font (size 1.27 1.27) (thickness 0.15)))
    )
    (property "License" "Apache-2.0" (at 107.95 135.89 0)
      (effects (font (size 1.27 1.27) (thickness 0.15)) (justify left bottom) hide)
    )
    (property "Author" "Antmicro" (at 107.95 138.43 0)
      (effects (font (size 1.27 1.27) (thickness 0.15)) (justify left bottom) hide)
    )
    (property "Tolerance" "1%" (at 107.95 120.65 0)
      (effects (font (size 1.27 1.27)) (justify left bottom) hide)
    )
    (pin "1")
    (pin "2")
    (instances
      (project "d1600e-psu-breakout-board"
        (path ""
          (reference "R1") (unit 1)
        )
      )
    )
  )

  (symbol (lib_id "antmicroUSBConnectors:USB-C_GCT_USB4145-03-0070-C") (at 306.07 50.8 0) (unit 1)
    (in_bom yes) (on_board yes) (dnp no)
    (property "Reference" "U1" (at 292.1 44.45 0)
      (effects (font (size 1.27 1.27)))
    )
    (property "Value" "USB-C_GCT_USB4145-03-0070-C" (at 327.66 58.42 0)
      (effects (font (size 1.27 1.27) (thickness 0.15)) (justify left bottom) hide)
    )
    (property "Footprint" "antmicro-footprints:USB-C_Receptacle_GCT_USB4145-03-0070-C" (at 327.66 60.96 0)
      (effects (font (size 1.27 1.27) (thickness 0.15)) (justify left bottom) hide)
    )
    (property "Datasheet" "https://gct.co/files/drawings/usb4145.pdf" (at 327.66 63.5 0)
      (effects (font (size 1.27 1.27) (thickness 0.15)) (justify left bottom) hide)
    )
    (property "MPN" "USB4145-03-0070-C" (at 292.1 46.99 0)
      (effects (font (size 1.27 1.27) (thickness 0.15)))
    )
    (property "Manufacturer" "GCT" (at 327.66 66.04 0)
      (effects (font (size 1.27 1.27) (thickness 0.15)) (justify left bottom) hide)
    )
    (property "License" "Apache-2.0" (at 327.66 68.58 0)
      (effects (font (size 1.27 1.27) (thickness 0.15)) (justify left bottom) hide)
    )
    (property "Author" "Antmicro" (at 327.66 71.12 0)
      (effects (font (size 1.27 1.27) (thickness 0.15)) (justify left bottom) hide)
    )
    (pin "A12")
    (pin "A5")
    (pin "A6")
    (pin "A7")
    (pin "A8")
    (pin "A9")
    (pin "B12")
    (pin "B5")
    (pin "B6")
    (pin "B7")
    (pin "B8")
    (pin "B9")
    (pin "B1")
    (pin "SH")
    (pin "A4")
    (pin "A1")
    (pin "B4")
    (instances
      (project "d1600e-psu-breakout-board"
        (path ""
          (reference "U1") (unit 1)
        )
      )
    )
  )

  (symbol (lib_id "antmicropower:GNDD") (at 95.25 167.64 0) (unit 1)
    (in_bom yes) (on_board yes) (dnp no) (fields_autoplaced)
    (property "Reference" "#PWR0119" (at 95.25 173.99 0)
      (effects (font (size 1.27 1.27)) hide)
    )
    (property "Value" "GNDD" (at 95.25 171.45 0)
      (effects (font (size 1.27 1.27) (thickness 0.15)))
    )
    (property "Footprint" "" (at 110.49 177.8 0)
      (effects (font (size 1.27 1.27) (thickness 0.15)) (justify left bottom) hide)
    )
    (property "Datasheet" "" (at 110.49 180.34 0)
      (effects (font (size 1.27 1.27) (thickness 0.15)) (justify left bottom) hide)
    )
    (property "Author" "Antmicro" (at 110.49 175.26 0)
      (effects (font (size 1.27 1.27) (thickness 0.15)) (justify left bottom) hide)
    )
    (property "License" "Apache-2.0" (at 110.49 177.8 0)
      (effects (font (size 1.27 1.27) (thickness 0.15)) (justify left bottom) hide)
    )
    (pin "1")
    (instances
      (project "d1600e-psu-breakout-board"
        (path ""
          (reference "#PWR0119") (unit 1)
        )
      )
    )
  )

  (symbol (lib_name "C_4u7_0402_2") (lib_id "antmicroCapacitors0402:C_4u7_0402") (at 63.5 90.17 90) (mirror x) (unit 1)
    (in_bom yes) (on_board yes) (dnp no)
    (property "Reference" "C12" (at 64.135 90.805 90)
      (effects (font (size 1.27 1.27)) (justify right))
    )
    (property "Value" "C_4u7_0402" (at 73.66 110.49 0)
      (effects (font (size 1.27 1.27) (thickness 0.15)) (justify left bottom) hide)
    )
    (property "Footprint" "antmicro-footprints:C_0402_1005Metric" (at 76.2 110.49 0)
      (effects (font (size 1.27 1.27) (thickness 0.15)) (justify left bottom) hide)
    )
    (property "Datasheet" "https://www.murata.com/products/productdetail?partno=GRM155R61A475MEAA%23" (at 78.74 110.49 0)
      (effects (font (size 1.27 1.27) (thickness 0.15)) (justify left bottom) hide)
    )
    (property "Manufacturer" "Murata" (at 83.82 110.49 0)
      (effects (font (size 1.27 1.27) (thickness 0.15)) (justify left bottom) hide)
    )
    (property "MPN" "GRM155R61A475MEAAD" (at 81.28 110.49 0)
      (effects (font (size 1.27 1.27) (thickness 0.15)) (justify left bottom) hide)
    )
    (property "Val" "4u7" (at 64.135 94.615 90)
      (effects (font (size 1.27 1.27) (thickness 0.15)) (justify right))
    )
    (property "License" "Apache-2.0" (at 86.36 110.49 0)
      (effects (font (size 1.27 1.27) (thickness 0.15)) (justify left bottom) hide)
    )
    (property "Author" "Antmicro" (at 88.9 110.49 0)
      (effects (font (size 1.27 1.27) (thickness 0.15)) (justify left bottom) hide)
    )
    (property "Voltage" "" (at 91.44 110.49 0)
      (effects (font (size 1.27 1.27)) (justify left bottom) hide)
    )
    (property "Dielectric" "" (at 93.98 110.49 0)
      (effects (font (size 1.27 1.27)) (justify left bottom) hide)
    )
    (pin "1")
    (pin "2")
    (instances
      (project "d1600e-psu-breakout-board"
        (path ""
          (reference "C12") (unit 1)
        )
      )
    )
  )

  (symbol (lib_name "R_0R_0603_2") (lib_id "antmicroResistors0603:R_0R_0603") (at 161.29 76.2 0) (unit 1)
    (in_bom yes) (on_board yes) (dnp no)
    (property "Reference" "R4" (at 167.64 74.93 0)
      (effects (font (size 1.27 1.27)))
    )
    (property "Value" "R_0R_0603" (at 181.61 88.9 0)
      (effects (font (size 1.27 1.27) (thickness 0.15)) (justify left bottom) hide)
    )
    (property "Footprint" "antmicro-footprints:R_0603_1608Metric" (at 181.61 91.44 0)
      (effects (font (size 1.27 1.27) (thickness 0.15)) (justify left bottom) hide)
    )
    (property "Datasheet" "https://www.bourns.com/docs/product-datasheets/cr.pdf?sfvrsn=574d41f6_14" (at 181.61 93.98 0)
      (effects (font (size 1.27 1.27) (thickness 0.15)) (justify left bottom) hide)
    )
    (property "Manufacturer" "Bourns" (at 181.61 99.06 0)
      (effects (font (size 1.27 1.27) (thickness 0.15)) (justify left bottom) hide)
    )
    (property "MPN" "CR0603-J/-000ELF" (at 181.61 96.52 0)
      (effects (font (size 1.27 1.27) (thickness 0.15)) (justify left bottom) hide)
    )
    (property "Val" "0R" (at 160.02 74.93 0)
      (effects (font (size 1.27 1.27) (thickness 0.15)))
    )
    (property "License" "Apache-2.0" (at 181.61 101.6 0)
      (effects (font (size 1.27 1.27) (thickness 0.15)) (justify left bottom) hide)
    )
    (property "Author" "Antmicro" (at 181.61 104.14 0)
      (effects (font (size 1.27 1.27) (thickness 0.15)) (justify left bottom) hide)
    )
    (property "Tolerance" "~" (at 181.61 86.36 0)
      (effects (font (size 1.27 1.27)) (justify left bottom) hide)
    )
    (property "Current" "1A" (at 181.61 106.68 0)
      (effects (font (size 1.27 1.27) (thickness 0.15)) (justify left bottom) hide)
    )
    (pin "1")
    (pin "2")
    (instances
      (project "d1600e-psu-breakout-board"
        (path ""
          (reference "R4") (unit 1)
        )
      )
    )
  )

  (symbol (lib_name "FB_600Z_0.5A_Murata-BLM18AG_0603_1") (lib_id "antmicroFerriteBeadsandChips:FB_600Z_0.5A_Murata-BLM18AG_0603") (at 53.34 83.82 0) (mirror y) (unit 1)
    (in_bom yes) (on_board yes) (dnp no) (fields_autoplaced)
    (property "Reference" "FB2" (at 50.8381 77.47 0)
      (effects (font (size 1.27 1.27)))
    )
    (property "Value" "FB_600Z_0.5A_Murata-BLM18AG_0603" (at 38.1 86.36 0)
      (effects (font (size 1.27 1.27) (thickness 0.15)) (justify left bottom) hide)
    )
    (property "Footprint" "antmicro-footprints:FB_0603_1608Metric" (at 38.1 91.44 0)
      (effects (font (size 1.27 1.27) (thickness 0.15)) (justify left bottom) hide)
    )
    (property "Datasheet" "https://www.murata.com/en-us/products/productdata/8796738650142/ENFA0003.pdf" (at 38.1 93.98 0)
      (effects (font (size 1.27 1.27) (thickness 0.15)) (justify left bottom) hide)
    )
    (property "MPN" "BLM18AG601SN1D" (at 38.1 96.52 0)
      (effects (font (size 1.27 1.27) (thickness 0.15)) (justify left bottom) hide)
    )
    (property "Manufacturer" "Murata" (at 38.1 99.06 0)
      (effects (font (size 1.27 1.27) (thickness 0.15)) (justify left bottom) hide)
    )
    (property "Val" "600Z/0.5A" (at 50.8381 80.01 0)
      (effects (font (size 1.27 1.27)))
    )
    (property "Current" "" (at 33.02 106.68 0)
      (effects (font (size 1.27 1.27) (thickness 0.15)) (justify left bottom) hide)
    )
    (property "Author" "Antmicro" (at 38.1 101.6 0)
      (effects (font (size 1.27 1.27) (thickness 0.15)) (justify left bottom) hide)
    )
    (property "License" "Apache-2.0" (at 38.1 104.14 0)
      (effects (font (size 1.27 1.27) (thickness 0.15)) (justify left bottom) hide)
    )
    (pin "1")
    (pin "2")
    (instances
      (project "d1600e-psu-breakout-board"
        (path ""
          (reference "FB2") (unit 1)
        )
      )
    )
  )

  (symbol (lib_id "antmicroResistors0402:R_5k1_0402") (at 321.31 58.42 0) (unit 1)
    (in_bom yes) (on_board yes) (dnp no)
    (property "Reference" "R58" (at 326.39 57.15 0)
      (effects (font (size 1.27 1.27)) (justify left))
    )
    (property "Value" "R_5k1_0402" (at 341.63 71.12 0)
      (effects (font (size 1.27 1.27) (thickness 0.15)) (justify left bottom) hide)
    )
    (property "Footprint" "antmicro-footprints:R_0402_1005Metric" (at 341.63 73.66 0)
      (effects (font (size 1.27 1.27) (thickness 0.15)) (justify left bottom) hide)
    )
    (property "Datasheet" "https://www.bourns.com/docs/product-datasheets/cr.pdf" (at 341.63 76.2 0)
      (effects (font (size 1.27 1.27) (thickness 0.15)) (justify left bottom) hide)
    )
    (property "Manufacturer" "Bourns" (at 341.63 81.28 0)
      (effects (font (size 1.27 1.27) (thickness 0.15)) (justify left bottom) hide)
    )
    (property "MPN" "CR0402-FX-5101GLF" (at 341.63 78.74 0)
      (effects (font (size 1.27 1.27) (thickness 0.15)) (justify left bottom) hide)
    )
    (property "Val" "5k1" (at 320.04 57.15 0)
      (effects (font (size 1.27 1.27) (thickness 0.15)))
    )
    (property "License" "Apache-2.0" (at 341.63 83.82 0)
      (effects (font (size 1.27 1.27) (thickness 0.15)) (justify left bottom) hide)
    )
    (property "Author" "Antmicro" (at 341.63 86.36 0)
      (effects (font (size 1.27 1.27) (thickness 0.15)) (justify left bottom) hide)
    )
    (property "Tolerance" "1%" (at 341.63 68.58 0)
      (effects (font (size 1.27 1.27)) (justify left bottom) hide)
    )
    (pin "1")
    (pin "2")
    (instances
      (project "d1600e-psu-breakout-board"
        (path ""
          (reference "R58") (unit 1)
        )
      )
    )
  )

  (symbol (lib_name "C_100n_0402_3") (lib_id "antmicroCapacitors0402:C_100n_0402") (at 205.74 95.25 180) (unit 1)
    (in_bom yes) (on_board yes) (dnp no)
    (property "Reference" "C5" (at 205.74 93.98 0)
      (effects (font (size 1.27 1.27)))
    )
    (property "Value" "C_100n_0402" (at 185.42 85.09 0)
      (effects (font (size 1.27 1.27) (thickness 0.15)) (justify left bottom) hide)
    )
    (property "Footprint" "antmicro-footprints:C_0402_1005Metric" (at 185.42 82.55 0)
      (effects (font (size 1.27 1.27) (thickness 0.15)) (justify left bottom) hide)
    )
    (property "Datasheet" "https://www.murata.com/products/productdetail?partno=GRM155R61H104KE14%23" (at 185.42 80.01 0)
      (effects (font (size 1.27 1.27) (thickness 0.15)) (justify left bottom) hide)
    )
    (property "Manufacturer" "Murata" (at 185.42 74.93 0)
      (effects (font (size 1.27 1.27) (thickness 0.15)) (justify left bottom) hide)
    )
    (property "MPN" "GRM155R61H104KE14D" (at 185.42 77.47 0)
      (effects (font (size 1.27 1.27) (thickness 0.15)) (justify left bottom) hide)
    )
    (property "Val" "100n" (at 199.39 93.98 0)
      (effects (font (size 1.27 1.27) (thickness 0.15)))
    )
    (property "License" "Apache-2.0" (at 185.42 72.39 0)
      (effects (font (size 1.27 1.27) (thickness 0.15)) (justify left bottom) hide)
    )
    (property "Author" "Antmicro" (at 185.42 69.85 0)
      (effects (font (size 1.27 1.27) (thickness 0.15)) (justify left bottom) hide)
    )
    (property "Voltage" "50V" (at 185.42 67.31 0)
      (effects (font (size 1.27 1.27)) (justify left bottom) hide)
    )
    (property "Dielectric" "X5R" (at 185.42 64.77 0)
      (effects (font (size 1.27 1.27)) (justify left bottom) hide)
    )
    (pin "1")
    (pin "2")
    (instances
      (project "d1600e-psu-breakout-board"
        (path ""
          (reference "C5") (unit 1)
        )
      )
    )
  )

  (symbol (lib_name "C_100n_0402_2") (lib_id "antmicroCapacitors0402:C_100n_0402") (at 81.28 90.17 90) (mirror x) (unit 1)
    (in_bom yes) (on_board yes) (dnp no)
    (property "Reference" "C15" (at 81.915 90.805 90)
      (effects (font (size 1.27 1.27)) (justify right))
    )
    (property "Value" "C_100n_0402" (at 91.44 110.49 0)
      (effects (font (size 1.27 1.27) (thickness 0.15)) (justify left bottom) hide)
    )
    (property "Footprint" "antmicro-footprints:C_0402_1005Metric" (at 93.98 110.49 0)
      (effects (font (size 1.27 1.27) (thickness 0.15)) (justify left bottom) hide)
    )
    (property "Datasheet" "https://www.murata.com/products/productdetail?partno=GRM155R61H104KE14%23" (at 96.52 110.49 0)
      (effects (font (size 1.27 1.27) (thickness 0.15)) (justify left bottom) hide)
    )
    (property "Manufacturer" "Murata" (at 101.6 110.49 0)
      (effects (font (size 1.27 1.27) (thickness 0.15)) (justify left bottom) hide)
    )
    (property "MPN" "GRM155R61H104KE14D" (at 99.06 110.49 0)
      (effects (font (size 1.27 1.27) (thickness 0.15)) (justify left bottom) hide)
    )
    (property "Val" "100n" (at 81.915 94.615 90)
      (effects (font (size 1.27 1.27) (thickness 0.15)) (justify right))
    )
    (property "License" "Apache-2.0" (at 104.14 110.49 0)
      (effects (font (size 1.27 1.27) (thickness 0.15)) (justify left bottom) hide)
    )
    (property "Author" "Antmicro" (at 106.68 110.49 0)
      (effects (font (size 1.27 1.27) (thickness 0.15)) (justify left bottom) hide)
    )
    (property "Voltage" "50V" (at 109.22 110.49 0)
      (effects (font (size 1.27 1.27)) (justify left bottom) hide)
    )
    (property "Dielectric" "X5R" (at 111.76 110.49 0)
      (effects (font (size 1.27 1.27)) (justify left bottom) hide)
    )
    (pin "1")
    (pin "2")
    (instances
      (project "d1600e-psu-breakout-board"
        (path ""
          (reference "C15") (unit 1)
        )
      )
    )
  )

  (symbol (lib_id "antmicroTestPoints:TP_1mm_SMD") (at 313.69 54.61 90) (unit 1)
    (in_bom no) (on_board yes) (dnp no)
    (property "Reference" "TP4" (at 313.69 49.53 90)
      (effects (font (size 1.27 1.27) (thickness 0.15)))
    )
    (property "Value" "TP_1mm_SMD" (at 321.31 39.37 0)
      (effects (font (size 1.27 1.27) (thickness 0.15)) (justify left bottom) hide)
    )
    (property "Footprint" "antmicro-footprints:TP_SMD_1mm" (at 323.85 39.37 0)
      (effects (font (size 1.27 1.27) (thickness 0.15)) (justify left bottom) hide)
    )
    (property "Datasheet" "" (at 326.39 36.83 0)
      (effects (font (size 1.27 1.27) (thickness 0.15)) (justify left bottom) hide)
    )
    (property "MPN" "" (at 313.69 54.61 0)
      (effects (font (size 1.27 1.27)) hide)
    )
    (property "Manufacturer" "" (at 313.69 54.61 0)
      (effects (font (size 1.27 1.27)) hide)
    )
    (property "Author" "Antmicro" (at 328.93 39.37 0)
      (effects (font (size 1.27 1.27) (thickness 0.15)) (justify left bottom) hide)
    )
    (property "License" "Apache-2.0" (at 331.47 39.37 0)
      (effects (font (size 1.27 1.27) (thickness 0.15)) (justify left bottom) hide)
    )
    (pin "1")
    (instances
      (project "d1600e-psu-breakout-board"
        (path ""
          (reference "TP4") (unit 1)
        )
      )
    )
  )

  (symbol (lib_id "antmicropower:GNDD") (at 54.61 97.79 0) (mirror y) (unit 1)
    (in_bom yes) (on_board yes) (dnp no) (fields_autoplaced)
    (property "Reference" "#PWR0120" (at 54.61 104.14 0)
      (effects (font (size 1.27 1.27)) hide)
    )
    (property "Value" "GNDD" (at 54.61 101.6 0)
      (effects (font (size 1.27 1.27) (thickness 0.15)))
    )
    (property "Footprint" "" (at 39.37 107.95 0)
      (effects (font (size 1.27 1.27) (thickness 0.15)) (justify left bottom) hide)
    )
    (property "Datasheet" "" (at 39.37 110.49 0)
      (effects (font (size 1.27 1.27) (thickness 0.15)) (justify left bottom) hide)
    )
    (property "Author" "Antmicro" (at 39.37 105.41 0)
      (effects (font (size 1.27 1.27) (thickness 0.15)) (justify left bottom) hide)
    )
    (property "License" "Apache-2.0" (at 39.37 107.95 0)
      (effects (font (size 1.27 1.27) (thickness 0.15)) (justify left bottom) hide)
    )
    (pin "1")
    (instances
      (project "d1600e-psu-breakout-board"
        (path ""
          (reference "#PWR0120") (unit 1)
        )
      )
    )
  )

  (symbol (lib_id "antmicropower:GND") (at 172.72 123.19 0) (unit 1)
    (in_bom yes) (on_board yes) (dnp no)
    (property "Reference" "#PWR020" (at 172.72 129.54 0)
      (effects (font (size 1.27 1.27)) hide)
    )
    (property "Value" "GND" (at 172.72 127 0)
      (effects (font (size 1.27 1.27) (thickness 0.15)))
    )
    (property "Footprint" "" (at 181.61 130.81 0)
      (effects (font (size 1.27 1.27) (thickness 0.15)) (justify left bottom) hide)
    )
    (property "Datasheet" "" (at 181.61 135.89 0)
      (effects (font (size 1.27 1.27) (thickness 0.15)) (justify left bottom) hide)
    )
    (property "Author" "Antmicro" (at 181.61 130.81 0)
      (effects (font (size 1.27 1.27) (thickness 0.15)) (justify left bottom) hide)
    )
    (property "License" "Apache-2.0" (at 181.61 133.35 0)
      (effects (font (size 1.27 1.27) (thickness 0.15)) (justify left bottom) hide)
    )
    (pin "1")
    (instances
      (project "d1600e-psu-breakout-board"
        (path ""
          (reference "#PWR020") (unit 1)
        )
      )
    )
  )

  (symbol (lib_id "antmicropower:GNDD") (at 313.69 41.91 0) (unit 1)
    (in_bom yes) (on_board yes) (dnp no) (fields_autoplaced)
    (property "Reference" "#PWR0136" (at 313.69 48.26 0)
      (effects (font (size 1.27 1.27)) hide)
    )
    (property "Value" "GNDD" (at 313.69 45.72 0)
      (effects (font (size 1.27 1.27) (thickness 0.15)))
    )
    (property "Footprint" "" (at 328.93 52.07 0)
      (effects (font (size 1.27 1.27) (thickness 0.15)) (justify left bottom) hide)
    )
    (property "Datasheet" "" (at 328.93 54.61 0)
      (effects (font (size 1.27 1.27) (thickness 0.15)) (justify left bottom) hide)
    )
    (property "Author" "Antmicro" (at 328.93 49.53 0)
      (effects (font (size 1.27 1.27) (thickness 0.15)) (justify left bottom) hide)
    )
    (property "License" "Apache-2.0" (at 328.93 52.07 0)
      (effects (font (size 1.27 1.27) (thickness 0.15)) (justify left bottom) hide)
    )
    (pin "1")
    (instances
      (project "d1600e-psu-breakout-board"
        (path ""
          (reference "#PWR0136") (unit 1)
        )
      )
    )
  )

  (symbol (lib_id "antmicroResistors0402:R_10k_0402") (at 177.8 101.6 270) (unit 1)
    (in_bom yes) (on_board yes) (dnp no)
    (property "Reference" "R73" (at 179.07 102.87 90)
      (effects (font (size 1.27 1.27)) (justify left))
    )
    (property "Value" "R_10k_0402" (at 165.1 121.92 0)
      (effects (font (size 1.27 1.27) (thickness 0.15)) (justify left bottom) hide)
    )
    (property "Footprint" "antmicro-footprints:R_0402_1005Metric" (at 162.56 121.92 0)
      (effects (font (size 1.27 1.27) (thickness 0.15)) (justify left bottom) hide)
    )
    (property "Datasheet" "https://www.bourns.com/docs/product-datasheets/cr.pdf" (at 160.02 121.92 0)
      (effects (font (size 1.27 1.27) (thickness 0.15)) (justify left bottom) hide)
    )
    (property "Manufacturer" "Bourns" (at 154.94 121.92 0)
      (effects (font (size 1.27 1.27) (thickness 0.15)) (justify left bottom) hide)
    )
    (property "MPN" "CR0402-FX-1002GLF" (at 157.48 121.92 0)
      (effects (font (size 1.27 1.27) (thickness 0.15)) (justify left bottom) hide)
    )
    (property "Val" "10k" (at 179.07 105.41 90)
      (effects (font (size 1.27 1.27) (thickness 0.15)) (justify left))
    )
    (property "License" "Apache-2.0" (at 152.4 121.92 0)
      (effects (font (size 1.27 1.27) (thickness 0.15)) (justify left bottom) hide)
    )
    (property "Author" "Antmicro" (at 149.86 121.92 0)
      (effects (font (size 1.27 1.27) (thickness 0.15)) (justify left bottom) hide)
    )
    (property "Tolerance" "1%" (at 167.64 121.92 0)
      (effects (font (size 1.27 1.27)) (justify left bottom) hide)
    )
    (pin "1")
    (pin "2")
    (instances
      (project "d1600e-psu-breakout-board"
        (path ""
          (reference "R73") (unit 1)
        )
      )
    )
  )

  (symbol (lib_name "C_100n_0402_1") (lib_id "antmicroCapacitors0402:C_100n_0402") (at 72.39 90.17 90) (mirror x) (unit 1)
    (in_bom yes) (on_board yes) (dnp no)
    (property "Reference" "C14" (at 73.025 90.805 90)
      (effects (font (size 1.27 1.27)) (justify right))
    )
    (property "Value" "C_100n_0402" (at 82.55 110.49 0)
      (effects (font (size 1.27 1.27) (thickness 0.15)) (justify left bottom) hide)
    )
    (property "Footprint" "antmicro-footprints:C_0402_1005Metric" (at 85.09 110.49 0)
      (effects (font (size 1.27 1.27) (thickness 0.15)) (justify left bottom) hide)
    )
    (property "Datasheet" "https://www.murata.com/products/productdetail?partno=GRM155R61H104KE14%23" (at 87.63 110.49 0)
      (effects (font (size 1.27 1.27) (thickness 0.15)) (justify left bottom) hide)
    )
    (property "Manufacturer" "Murata" (at 92.71 110.49 0)
      (effects (font (size 1.27 1.27) (thickness 0.15)) (justify left bottom) hide)
    )
    (property "MPN" "GRM155R61H104KE14D" (at 90.17 110.49 0)
      (effects (font (size 1.27 1.27) (thickness 0.15)) (justify left bottom) hide)
    )
    (property "Val" "100n" (at 73.025 94.615 90)
      (effects (font (size 1.27 1.27) (thickness 0.15)) (justify right))
    )
    (property "License" "Apache-2.0" (at 95.25 110.49 0)
      (effects (font (size 1.27 1.27) (thickness 0.15)) (justify left bottom) hide)
    )
    (property "Author" "Antmicro" (at 97.79 110.49 0)
      (effects (font (size 1.27 1.27) (thickness 0.15)) (justify left bottom) hide)
    )
    (property "Voltage" "50V" (at 100.33 110.49 0)
      (effects (font (size 1.27 1.27)) (justify left bottom) hide)
    )
    (property "Dielectric" "X5R" (at 102.87 110.49 0)
      (effects (font (size 1.27 1.27)) (justify left bottom) hide)
    )
    (pin "1")
    (pin "2")
    (instances
      (project "d1600e-psu-breakout-board"
        (path ""
          (reference "C14") (unit 1)
        )
      )
    )
  )

  (symbol (lib_name "R_0R_0603_1") (lib_id "antmicroResistors0603:R_0R_0603") (at 156.21 97.79 0) (unit 1)
    (in_bom no) (on_board yes) (dnp yes)
    (property "Reference" "R75" (at 158.75 92.71 0)
      (effects (font (size 1.27 1.27)))
    )
    (property "Value" "R_0R_0603" (at 176.53 110.49 0)
      (effects (font (size 1.27 1.27) (thickness 0.15)) (justify left bottom) hide)
    )
    (property "Footprint" "antmicro-footprints:R_0603_1608Metric" (at 176.53 113.03 0)
      (effects (font (size 1.27 1.27) (thickness 0.15)) (justify left bottom) hide)
    )
    (property "Datasheet" "https://www.bourns.com/docs/product-datasheets/cr.pdf?sfvrsn=574d41f6_14" (at 176.53 115.57 0)
      (effects (font (size 1.27 1.27) (thickness 0.15)) (justify left bottom) hide)
    )
    (property "Manufacturer" "Bourns" (at 176.53 120.65 0)
      (effects (font (size 1.27 1.27) (thickness 0.15)) (justify left bottom) hide)
    )
    (property "MPN" "CR0603-J/-000ELF" (at 176.53 118.11 0)
      (effects (font (size 1.27 1.27) (thickness 0.15)) (justify left bottom) hide)
    )
    (property "Val" "0R" (at 158.75 95.25 0)
      (effects (font (size 1.27 1.27) (thickness 0.15)))
    )
    (property "DNP" "DNP" (at 158.75 100.33 0)
      (effects (font (size 1.27 1.27)))
    )
    (property "License" "Apache-2.0" (at 176.53 123.19 0)
      (effects (font (size 1.27 1.27) (thickness 0.15)) (justify left bottom) hide)
    )
    (property "Author" "Antmicro" (at 176.53 125.73 0)
      (effects (font (size 1.27 1.27) (thickness 0.15)) (justify left bottom) hide)
    )
    (property "Tolerance" "~" (at 176.53 107.95 0)
      (effects (font (size 1.27 1.27)) (justify left bottom) hide)
    )
    (property "Current" "1A" (at 176.53 128.27 0)
      (effects (font (size 1.27 1.27) (thickness 0.15)) (justify left bottom) hide)
    )
    (pin "1")
    (pin "2")
    (instances
      (project "d1600e-psu-breakout-board"
        (path ""
          (reference "R75") (unit 1)
        )
      )
    )
  )

  (symbol (lib_id "antmicropower:GNDD") (at 153.67 123.19 0) (unit 1)
    (in_bom yes) (on_board yes) (dnp no) (fields_autoplaced)
    (property "Reference" "#PWR024" (at 153.67 129.54 0)
      (effects (font (size 1.27 1.27)) hide)
    )
    (property "Value" "GNDD" (at 153.67 127 0)
      (effects (font (size 1.27 1.27) (thickness 0.15)))
    )
    (property "Footprint" "" (at 168.91 133.35 0)
      (effects (font (size 1.27 1.27) (thickness 0.15)) (justify left bottom) hide)
    )
    (property "Datasheet" "" (at 168.91 135.89 0)
      (effects (font (size 1.27 1.27) (thickness 0.15)) (justify left bottom) hide)
    )
    (property "Author" "Antmicro" (at 168.91 130.81 0)
      (effects (font (size 1.27 1.27) (thickness 0.15)) (justify left bottom) hide)
    )
    (property "License" "Apache-2.0" (at 168.91 133.35 0)
      (effects (font (size 1.27 1.27) (thickness 0.15)) (justify left bottom) hide)
    )
    (pin "1")
    (instances
      (project "d1600e-psu-breakout-board"
        (path ""
          (reference "#PWR024") (unit 1)
        )
      )
    )
  )

  (symbol (lib_id "antmicroTestPoints:TP_1mm_SMD") (at 322.58 54.61 90) (unit 1)
    (in_bom no) (on_board yes) (dnp no)
    (property "Reference" "TP1" (at 322.58 49.53 90)
      (effects (font (size 1.27 1.27) (thickness 0.15)))
    )
    (property "Value" "TP_1mm_SMD" (at 330.2 39.37 0)
      (effects (font (size 1.27 1.27) (thickness 0.15)) (justify left bottom) hide)
    )
    (property "Footprint" "antmicro-footprints:TP_SMD_1mm" (at 332.74 39.37 0)
      (effects (font (size 1.27 1.27) (thickness 0.15)) (justify left bottom) hide)
    )
    (property "Datasheet" "" (at 335.28 36.83 0)
      (effects (font (size 1.27 1.27) (thickness 0.15)) (justify left bottom) hide)
    )
    (property "MPN" "" (at 322.58 54.61 0)
      (effects (font (size 1.27 1.27)) hide)
    )
    (property "Manufacturer" "" (at 322.58 54.61 0)
      (effects (font (size 1.27 1.27)) hide)
    )
    (property "Author" "Antmicro" (at 337.82 39.37 0)
      (effects (font (size 1.27 1.27) (thickness 0.15)) (justify left bottom) hide)
    )
    (property "License" "Apache-2.0" (at 340.36 39.37 0)
      (effects (font (size 1.27 1.27) (thickness 0.15)) (justify left bottom) hide)
    )
    (pin "1")
    (instances
      (project "d1600e-psu-breakout-board"
        (path ""
          (reference "TP1") (unit 1)
        )
      )
    )
  )

  (symbol (lib_name "C_4u7_0402_1") (lib_id "antmicroCapacitors0402:C_4u7_0402") (at 54.61 90.17 90) (mirror x) (unit 1)
    (in_bom yes) (on_board yes) (dnp no)
    (property "Reference" "C11" (at 55.245 90.805 90)
      (effects (font (size 1.27 1.27)) (justify right))
    )
    (property "Value" "C_4u7_0402" (at 64.77 110.49 0)
      (effects (font (size 1.27 1.27) (thickness 0.15)) (justify left bottom) hide)
    )
    (property "Footprint" "antmicro-footprints:C_0402_1005Metric" (at 67.31 110.49 0)
      (effects (font (size 1.27 1.27) (thickness 0.15)) (justify left bottom) hide)
    )
    (property "Datasheet" "https://www.murata.com/products/productdetail?partno=GRM155R61A475MEAA%23" (at 69.85 110.49 0)
      (effects (font (size 1.27 1.27) (thickness 0.15)) (justify left bottom) hide)
    )
    (property "Manufacturer" "Murata" (at 74.93 110.49 0)
      (effects (font (size 1.27 1.27) (thickness 0.15)) (justify left bottom) hide)
    )
    (property "MPN" "GRM155R61A475MEAAD" (at 72.39 110.49 0)
      (effects (font (size 1.27 1.27) (thickness 0.15)) (justify left bottom) hide)
    )
    (property "Val" "4u7" (at 59.055 94.615 90)
      (effects (font (size 1.27 1.27) (thickness 0.15)) (justify left))
    )
    (property "License" "Apache-2.0" (at 77.47 110.49 0)
      (effects (font (size 1.27 1.27) (thickness 0.15)) (justify left bottom) hide)
    )
    (property "Author" "Antmicro" (at 80.01 110.49 0)
      (effects (font (size 1.27 1.27) (thickness 0.15)) (justify left bottom) hide)
    )
    (property "Voltage" "" (at 82.55 110.49 0)
      (effects (font (size 1.27 1.27)) (justify left bottom) hide)
    )
    (property "Dielectric" "" (at 85.09 110.49 0)
      (effects (font (size 1.27 1.27)) (justify left bottom) hide)
    )
    (pin "1")
    (pin "2")
    (instances
      (project "d1600e-psu-breakout-board"
        (path ""
          (reference "C11") (unit 1)
        )
      )
    )
  )

  (symbol (lib_id "antmicropower:GNDD") (at 102.87 167.64 0) (unit 1)
    (in_bom yes) (on_board yes) (dnp no) (fields_autoplaced)
    (property "Reference" "#PWR0115" (at 102.87 173.99 0)
      (effects (font (size 1.27 1.27)) hide)
    )
    (property "Value" "GNDD" (at 102.87 171.45 0)
      (effects (font (size 1.27 1.27) (thickness 0.15)))
    )
    (property "Footprint" "" (at 118.11 177.8 0)
      (effects (font (size 1.27 1.27) (thickness 0.15)) (justify left bottom) hide)
    )
    (property "Datasheet" "" (at 118.11 180.34 0)
      (effects (font (size 1.27 1.27) (thickness 0.15)) (justify left bottom) hide)
    )
    (property "Author" "Antmicro" (at 118.11 175.26 0)
      (effects (font (size 1.27 1.27) (thickness 0.15)) (justify left bottom) hide)
    )
    (property "License" "Apache-2.0" (at 118.11 177.8 0)
      (effects (font (size 1.27 1.27) (thickness 0.15)) (justify left bottom) hide)
    )
    (pin "1")
    (instances
      (project "d1600e-psu-breakout-board"
        (path ""
          (reference "#PWR0115") (unit 1)
        )
      )
    )
  )

  (symbol (lib_id "antmicroTestPoints:TP_1mm_SMD") (at 151.13 81.28 0) (unit 1)
    (in_bom no) (on_board yes) (dnp no) (fields_autoplaced)
    (property "Reference" "WP1" (at 156.21 81.28 0)
      (effects (font (size 1.27 1.27)) (justify left))
    )
    (property "Value" "TP_1mm_SMD" (at 166.37 88.9 0)
      (effects (font (size 1.27 1.27) (thickness 0.15)) (justify left bottom) hide)
    )
    (property "Footprint" "antmicro-footprints:TP_SMD_1mm" (at 166.37 91.44 0)
      (effects (font (size 1.27 1.27) (thickness 0.15)) (justify left bottom) hide)
    )
    (property "Datasheet" "" (at 168.91 93.98 0)
      (effects (font (size 1.27 1.27) (thickness 0.15)) (justify left bottom) hide)
    )
    (property "MPN" "" (at 151.13 81.28 0)
      (effects (font (size 1.27 1.27)) hide)
    )
    (property "Manufacturer" "" (at 151.13 81.28 0)
      (effects (font (size 1.27 1.27)) hide)
    )
    (property "Author" "Antmicro" (at 166.37 96.52 0)
      (effects (font (size 1.27 1.27) (thickness 0.15)) (justify left bottom) hide)
    )
    (property "License" "Apache-2.0" (at 166.37 99.06 0)
      (effects (font (size 1.27 1.27) (thickness 0.15)) (justify left bottom) hide)
    )
    (pin "1")
    (instances
      (project "d1600e-psu-breakout-board"
        (path ""
          (reference "WP1") (unit 1)
        )
      )
    )
  )

  (symbol (lib_name "R_4k7_0402_1") (lib_id "antmicroResistors0402:R_4k7_0402") (at 172.72 68.58 90) (unit 1)
    (in_bom yes) (on_board yes) (dnp no)
    (property "Reference" "R6" (at 173.99 64.77 90)
      (effects (font (size 1.27 1.27)) (justify right))
    )
    (property "Value" "R_4k7_0402" (at 185.42 48.26 0)
      (effects (font (size 1.27 1.27) (thickness 0.15)) (justify left bottom) hide)
    )
    (property "Footprint" "antmicro-footprints:R_0402_1005Metric" (at 187.96 48.26 0)
      (effects (font (size 1.27 1.27) (thickness 0.15)) (justify left bottom) hide)
    )
    (property "Datasheet" "https://www.bourns.com/docs/product-datasheets/cr.pdf" (at 190.5 48.26 0)
      (effects (font (size 1.27 1.27) (thickness 0.15)) (justify left bottom) hide)
    )
    (property "Manufacturer" "Bourns" (at 195.58 48.26 0)
      (effects (font (size 1.27 1.27) (thickness 0.15)) (justify left bottom) hide)
    )
    (property "MPN" "CR0402-FX-4701GLF" (at 193.04 48.26 0)
      (effects (font (size 1.27 1.27) (thickness 0.15)) (justify left bottom) hide)
    )
    (property "Val" "4k7" (at 173.99 67.31 90)
      (effects (font (size 1.27 1.27) (thickness 0.15)) (justify right))
    )
    (property "License" "Apache-2.0" (at 198.12 48.26 0)
      (effects (font (size 1.27 1.27) (thickness 0.15)) (justify left bottom) hide)
    )
    (property "Author" "Antmicro" (at 200.66 48.26 0)
      (effects (font (size 1.27 1.27) (thickness 0.15)) (justify left bottom) hide)
    )
    (property "Tolerance" "1%" (at 182.88 48.26 0)
      (effects (font (size 1.27 1.27)) (justify left bottom) hide)
    )
    (pin "1")
    (pin "2")
    (instances
      (project "d1600e-psu-breakout-board"
        (path ""
          (reference "R6") (unit 1)
        )
      )
    )
  )

  (symbol (lib_id "antmicroResistors0402:R_220R_0402") (at 153.67 121.92 90) (unit 1)
    (in_bom yes) (on_board yes) (dnp no)
    (property "Reference" "R74" (at 154.94 118.11 90)
      (effects (font (size 1.27 1.27) (thickness 0.15)) (justify right))
    )
    (property "Value" "R_220R_0402" (at 166.37 101.6 0)
      (effects (font (size 1.27 1.27) (thickness 0.15)) (justify left bottom) hide)
    )
    (property "Footprint" "antmicro-footprints:R_0402_1005Metric" (at 168.91 101.6 0)
      (effects (font (size 1.27 1.27) (thickness 0.15)) (justify left bottom) hide)
    )
    (property "Datasheet" "https://www.bourns.com/docs/product-datasheets/cr.pdf" (at 171.45 101.6 0)
      (effects (font (size 1.27 1.27) (thickness 0.15)) (justify left bottom) hide)
    )
    (property "MPN" "CR0402-FX-2200GLF" (at 173.99 101.6 0)
      (effects (font (size 1.27 1.27) (thickness 0.15)) (justify left bottom) hide)
    )
    (property "Manufacturer" "Bourns" (at 176.53 101.6 0)
      (effects (font (size 1.27 1.27) (thickness 0.15)) (justify left bottom) hide)
    )
    (property "License" "Apache-2.0" (at 179.07 101.6 0)
      (effects (font (size 1.27 1.27) (thickness 0.15)) (justify left bottom) hide)
    )
    (property "Author" "Antmicro" (at 181.61 101.6 0)
      (effects (font (size 1.27 1.27) (thickness 0.15)) (justify left bottom) hide)
    )
    (property "Val" "220R" (at 154.94 120.65 90)
      (effects (font (size 1.27 1.27) (thickness 0.15)) (justify right))
    )
    (property "Tolerance" "1%" (at 163.83 101.6 0)
      (effects (font (size 1.27 1.27)) (justify left bottom) hide)
    )
    (pin "1")
    (pin "2")
    (instances
      (project "d1600e-psu-breakout-board"
        (path ""
          (reference "R74") (unit 1)
        )
      )
    )
  )

  (symbol (lib_id "antmicropower:GNDD") (at 339.09 60.96 0) (mirror y) (unit 1)
    (in_bom yes) (on_board yes) (dnp no) (fields_autoplaced)
    (property "Reference" "#PWR0126" (at 339.09 67.31 0)
      (effects (font (size 1.27 1.27)) hide)
    )
    (property "Value" "GNDD" (at 339.09 64.77 0)
      (effects (font (size 1.27 1.27) (thickness 0.15)))
    )
    (property "Footprint" "" (at 323.85 71.12 0)
      (effects (font (size 1.27 1.27) (thickness 0.15)) (justify left bottom) hide)
    )
    (property "Datasheet" "" (at 323.85 73.66 0)
      (effects (font (size 1.27 1.27) (thickness 0.15)) (justify left bottom) hide)
    )
    (property "Author" "Antmicro" (at 323.85 68.58 0)
      (effects (font (size 1.27 1.27) (thickness 0.15)) (justify left bottom) hide)
    )
    (property "License" "Apache-2.0" (at 323.85 71.12 0)
      (effects (font (size 1.27 1.27) (thickness 0.15)) (justify left bottom) hide)
    )
    (pin "1")
    (instances
      (project "d1600e-psu-breakout-board"
        (path ""
          (reference "#PWR0126") (unit 1)
        )
      )
    )
  )

  (symbol (lib_id "antmicroCapacitors0402:C_18p_0402") (at 73.66 142.24 90) (unit 1)
    (in_bom yes) (on_board yes) (dnp no)
    (property "Reference" "C2" (at 74.295 137.795 90)
      (effects (font (size 1.27 1.27)) (justify right))
    )
    (property "Value" "C_18p_0402" (at 83.82 121.92 0)
      (effects (font (size 1.27 1.27) (thickness 0.15)) (justify left bottom) hide)
    )
    (property "Footprint" "antmicro-footprints:C_0402_1005Metric" (at 86.36 121.92 0)
      (effects (font (size 1.27 1.27) (thickness 0.15)) (justify left bottom) hide)
    )
    (property "Datasheet" "https://product.samsungsem.com/mlcc/CL05C180JB51PN.do" (at 88.9 121.92 0)
      (effects (font (size 1.27 1.27) (thickness 0.15)) (justify left bottom) hide)
    )
    (property "Manufacturer" "Samsung Electro-Mechanics" (at 93.98 121.92 0)
      (effects (font (size 1.27 1.27) (thickness 0.15)) (justify left bottom) hide)
    )
    (property "MPN" "CL05C180JB51PNC" (at 91.44 121.92 0)
      (effects (font (size 1.27 1.27) (thickness 0.15)) (justify left bottom) hide)
    )
    (property "Val" "18p" (at 74.295 141.605 90)
      (effects (font (size 1.27 1.27) (thickness 0.15)) (justify right))
    )
    (property "License" "Apache-2.0" (at 96.52 121.92 0)
      (effects (font (size 1.27 1.27) (thickness 0.15)) (justify left bottom) hide)
    )
    (property "Author" "Antmicro" (at 99.06 121.92 0)
      (effects (font (size 1.27 1.27) (thickness 0.15)) (justify left bottom) hide)
    )
    (property "Voltage" "" (at 101.6 121.92 0)
      (effects (font (size 1.27 1.27)) (justify left bottom) hide)
    )
    (property "Dielectric" "" (at 104.14 121.92 0)
      (effects (font (size 1.27 1.27)) (justify left bottom) hide)
    )
    (pin "1")
    (pin "2")
    (instances
      (project "d1600e-psu-breakout-board"
        (path ""
          (reference "C2") (unit 1)
        )
      )
    )
  )

  (symbol (lib_id "antmicroTestPoints:TP_1mm_SMD") (at 307.34 76.2 0) (unit 1)
    (in_bom no) (on_board yes) (dnp no) (fields_autoplaced)
    (property "Reference" "TP2" (at 312.42 76.2 0)
      (effects (font (size 1.27 1.27) (thickness 0.15)) (justify left))
    )
    (property "Value" "TP_1mm_SMD" (at 322.58 83.82 0)
      (effects (font (size 1.27 1.27) (thickness 0.15)) (justify left bottom) hide)
    )
    (property "Footprint" "antmicro-footprints:TP_SMD_1mm" (at 322.58 86.36 0)
      (effects (font (size 1.27 1.27) (thickness 0.15)) (justify left bottom) hide)
    )
    (property "Datasheet" "" (at 325.12 88.9 0)
      (effects (font (size 1.27 1.27) (thickness 0.15)) (justify left bottom) hide)
    )
    (property "MPN" "" (at 307.34 76.2 0)
      (effects (font (size 1.27 1.27)) hide)
    )
    (property "Manufacturer" "" (at 307.34 76.2 0)
      (effects (font (size 1.27 1.27)) hide)
    )
    (property "Author" "Antmicro" (at 322.58 91.44 0)
      (effects (font (size 1.27 1.27) (thickness 0.15)) (justify left bottom) hide)
    )
    (property "License" "Apache-2.0" (at 322.58 93.98 0)
      (effects (font (size 1.27 1.27) (thickness 0.15)) (justify left bottom) hide)
    )
    (pin "1")
    (instances
      (project "d1600e-psu-breakout-board"
        (path ""
          (reference "TP2") (unit 1)
        )
      )
    )
  )

  (symbol (lib_id "antmicroLogicBuffersDriversReceiversTransceivers:SN74AUP1G17_SC70") (at 187.96 106.68 0) (unit 1)
    (in_bom yes) (on_board yes) (dnp no)
    (property "Reference" "U6" (at 196.85 100.33 0)
      (effects (font (size 1.27 1.27) (thickness 0.15)))
    )
    (property "Value" "SN74AUP1G17_SC70" (at 220.98 111.76 0)
      (effects (font (size 1.27 1.27) (thickness 0.15)) (justify left bottom) hide)
    )
    (property "Footprint" "antmicro-footprints:SC-70-5" (at 220.98 114.3 0)
      (effects (font (size 1.27 1.27) (thickness 0.15)) (justify left bottom) hide)
    )
    (property "Datasheet" "https://www.ti.com/lit/ds/symlink/sn74aup1g17.pdf" (at 220.98 116.84 0)
      (effects (font (size 1.27 1.27) (thickness 0.15)) (justify left bottom) hide)
    )
    (property "MPN" "SN74AUP1G17DCKR" (at 187.96 102.87 0)
      (effects (font (size 1.27 1.27) (thickness 0.15)) (justify left))
    )
    (property "Manufacturer" "Texas Instruments" (at 220.98 121.92 0)
      (effects (font (size 1.27 1.27) (thickness 0.15)) (justify left bottom) hide)
    )
    (property "Author" "Antmicro" (at 220.98 124.46 0)
      (effects (font (size 1.27 1.27) (thickness 0.15)) (justify left bottom) hide)
    )
    (property "License" "Apache-2.0" (at 220.98 127 0)
      (effects (font (size 1.27 1.27) (thickness 0.15)) (justify left bottom) hide)
    )
    (pin "1")
    (pin "2")
    (pin "3")
    (pin "4")
    (pin "5")
    (instances
      (project "d1600e-psu-breakout-board"
        (path ""
          (reference "U6") (unit 1)
        )
      )
    )
  )

  (symbol (lib_id "antmicroResistors0402:R_12k_0402") (at 95.25 162.56 90) (unit 1)
    (in_bom yes) (on_board yes) (dnp no)
    (property "Reference" "R3" (at 96.52 158.75 90)
      (effects (font (size 1.27 1.27)) (justify right))
    )
    (property "Value" "R_12k_0402" (at 107.95 142.24 0)
      (effects (font (size 1.27 1.27) (thickness 0.15)) (justify left bottom) hide)
    )
    (property "Footprint" "antmicro-footprints:R_0402_1005Metric" (at 110.49 142.24 0)
      (effects (font (size 1.27 1.27) (thickness 0.15)) (justify left bottom) hide)
    )
    (property "Datasheet" "https://www.bourns.com/docs/product-datasheets/cr.pdf" (at 113.03 142.24 0)
      (effects (font (size 1.27 1.27) (thickness 0.15)) (justify left bottom) hide)
    )
    (property "Manufacturer" "Bourns" (at 118.11 142.24 0)
      (effects (font (size 1.27 1.27) (thickness 0.15)) (justify left bottom) hide)
    )
    (property "MPN" "CR0402-FX-1202GLF" (at 115.57 142.24 0)
      (effects (font (size 1.27 1.27) (thickness 0.15)) (justify left bottom) hide)
    )
    (property "Val" "12k" (at 96.52 161.29 90)
      (effects (font (size 1.27 1.27) (thickness 0.15)) (justify right))
    )
    (property "License" "Apache-2.0" (at 120.65 142.24 0)
      (effects (font (size 1.27 1.27) (thickness 0.15)) (justify left bottom) hide)
    )
    (property "Author" "Antmicro" (at 123.19 142.24 0)
      (effects (font (size 1.27 1.27) (thickness 0.15)) (justify left bottom) hide)
    )
    (property "Tolerance" "1%" (at 105.41 142.24 0)
      (effects (font (size 1.27 1.27)) (justify left bottom) hide)
    )
    (pin "1")
    (pin "2")
    (instances
      (project "d1600e-psu-breakout-board"
        (path ""
          (reference "R3") (unit 1)
        )
      )
    )
  )

  (symbol (lib_id "antmicroTestPoints:TP_1mm_SMD") (at 307.34 78.74 0) (unit 1)
    (in_bom no) (on_board yes) (dnp no) (fields_autoplaced)
    (property "Reference" "TP3" (at 312.42 78.74 0)
      (effects (font (size 1.27 1.27) (thickness 0.15)) (justify left))
    )
    (property "Value" "TP_1mm_SMD" (at 322.58 86.36 0)
      (effects (font (size 1.27 1.27) (thickness 0.15)) (justify left bottom) hide)
    )
    (property "Footprint" "antmicro-footprints:TP_SMD_1mm" (at 322.58 88.9 0)
      (effects (font (size 1.27 1.27) (thickness 0.15)) (justify left bottom) hide)
    )
    (property "Datasheet" "" (at 325.12 91.44 0)
      (effects (font (size 1.27 1.27) (thickness 0.15)) (justify left bottom) hide)
    )
    (property "MPN" "" (at 307.34 78.74 0)
      (effects (font (size 1.27 1.27)) hide)
    )
    (property "Manufacturer" "" (at 307.34 78.74 0)
      (effects (font (size 1.27 1.27)) hide)
    )
    (property "Author" "Antmicro" (at 322.58 93.98 0)
      (effects (font (size 1.27 1.27) (thickness 0.15)) (justify left bottom) hide)
    )
    (property "License" "Apache-2.0" (at 322.58 96.52 0)
      (effects (font (size 1.27 1.27) (thickness 0.15)) (justify left bottom) hide)
    )
    (pin "1")
    (instances
      (project "d1600e-psu-breakout-board"
        (path ""
          (reference "TP3") (unit 1)
        )
      )
    )
  )

  (symbol (lib_name "R_5k1_0402_1") (lib_id "antmicroResistors0402:R_5k1_0402") (at 336.55 55.88 0) (mirror y) (unit 1)
    (in_bom yes) (on_board yes) (dnp no)
    (property "Reference" "R57" (at 336.55 54.61 0)
      (effects (font (size 1.27 1.27)) (justify right))
    )
    (property "Value" "R_5k1_0402" (at 316.23 68.58 0)
      (effects (font (size 1.27 1.27) (thickness 0.15)) (justify left bottom) hide)
    )
    (property "Footprint" "antmicro-footprints:R_0402_1005Metric" (at 316.23 71.12 0)
      (effects (font (size 1.27 1.27) (thickness 0.15)) (justify left bottom) hide)
    )
    (property "Datasheet" "https://www.bourns.com/docs/product-datasheets/cr.pdf" (at 316.23 73.66 0)
      (effects (font (size 1.27 1.27) (thickness 0.15)) (justify left bottom) hide)
    )
    (property "Manufacturer" "Bourns" (at 316.23 78.74 0)
      (effects (font (size 1.27 1.27) (thickness 0.15)) (justify left bottom) hide)
    )
    (property "MPN" "CR0402-FX-5101GLF" (at 316.23 76.2 0)
      (effects (font (size 1.27 1.27) (thickness 0.15)) (justify left bottom) hide)
    )
    (property "Val" "5k1" (at 330.2 54.61 0)
      (effects (font (size 1.27 1.27) (thickness 0.15)))
    )
    (property "License" "Apache-2.0" (at 316.23 81.28 0)
      (effects (font (size 1.27 1.27) (thickness 0.15)) (justify left bottom) hide)
    )
    (property "Author" "Antmicro" (at 316.23 83.82 0)
      (effects (font (size 1.27 1.27) (thickness 0.15)) (justify left bottom) hide)
    )
    (property "Tolerance" "1%" (at 316.23 66.04 0)
      (effects (font (size 1.27 1.27)) (justify left bottom) hide)
    )
    (pin "1")
    (pin "2")
    (instances
      (project "d1600e-psu-breakout-board"
        (path ""
          (reference "R57") (unit 1)
        )
      )
    )
  )

  (symbol (lib_id "antmicropower:GNDD") (at 63.5 97.79 0) (mirror y) (unit 1)
    (in_bom yes) (on_board yes) (dnp no) (fields_autoplaced)
    (property "Reference" "#PWR0117" (at 63.5 104.14 0)
      (effects (font (size 1.27 1.27)) hide)
    )
    (property "Value" "GNDD" (at 63.5 101.6 0)
      (effects (font (size 1.27 1.27) (thickness 0.15)))
    )
    (property "Footprint" "" (at 48.26 107.95 0)
      (effects (font (size 1.27 1.27) (thickness 0.15)) (justify left bottom) hide)
    )
    (property "Datasheet" "" (at 48.26 110.49 0)
      (effects (font (size 1.27 1.27) (thickness 0.15)) (justify left bottom) hide)
    )
    (property "Author" "Antmicro" (at 48.26 105.41 0)
      (effects (font (size 1.27 1.27) (thickness 0.15)) (justify left bottom) hide)
    )
    (property "License" "Apache-2.0" (at 48.26 107.95 0)
      (effects (font (size 1.27 1.27) (thickness 0.15)) (justify left bottom) hide)
    )
    (pin "1")
    (instances
      (project "d1600e-psu-breakout-board"
        (path ""
          (reference "#PWR0117") (unit 1)
        )
      )
    )
  )

  (symbol (lib_id "antmicroResistors0402:R_4k7_0402") (at 140.97 238.76 90) (unit 1)
    (in_bom yes) (on_board yes) (dnp no)
    (property "Reference" "R37" (at 142.24 234.95 90)
      (effects (font (size 1.27 1.27)) (justify right))
    )
    (property "Value" "R_4k7_0402" (at 153.67 218.44 0)
      (effects (font (size 1.27 1.27) (thickness 0.15)) (justify left bottom) hide)
    )
    (property "Footprint" "antmicro-footprints:R_0402_1005Metric" (at 156.21 218.44 0)
      (effects (font (size 1.27 1.27) (thickness 0.15)) (justify left bottom) hide)
    )
    (property "Datasheet" "https://www.bourns.com/docs/product-datasheets/cr.pdf" (at 158.75 218.44 0)
      (effects (font (size 1.27 1.27) (thickness 0.15)) (justify left bottom) hide)
    )
    (property "Manufacturer" "Bourns" (at 163.83 218.44 0)
      (effects (font (size 1.27 1.27) (thickness 0.15)) (justify left bottom) hide)
    )
    (property "MPN" "CR0402-FX-4701GLF" (at 161.29 218.44 0)
      (effects (font (size 1.27 1.27) (thickness 0.15)) (justify left bottom) hide)
    )
    (property "Val" "4k7" (at 142.24 237.49 90)
      (effects (font (size 1.27 1.27) (thickness 0.15)) (justify right))
    )
    (property "License" "Apache-2.0" (at 166.37 218.44 0)
      (effects (font (size 1.27 1.27) (thickness 0.15)) (justify left bottom) hide)
    )
    (property "Author" "Antmicro" (at 168.91 218.44 0)
      (effects (font (size 1.27 1.27) (thickness 0.15)) (justify left bottom) hide)
    )
    (property "Tolerance" "1%" (at 151.13 218.44 0)
      (effects (font (size 1.27 1.27)) (justify left bottom) hide)
    )
    (pin "1")
    (pin "2")
    (instances
      (project "d1600e-psu-breakout-board"
        (path ""
          (reference "R37") (unit 1)
        )
      )
    )
  )

  (symbol (lib_id "antmicropower:GND") (at 212.09 99.06 0) (unit 1)
    (in_bom yes) (on_board yes) (dnp no)
    (property "Reference" "#PWR019" (at 212.09 105.41 0)
      (effects (font (size 1.27 1.27)) hide)
    )
    (property "Value" "GND" (at 212.09 102.87 0)
      (effects (font (size 1.27 1.27) (thickness 0.15)))
    )
    (property "Footprint" "" (at 220.98 106.68 0)
      (effects (font (size 1.27 1.27) (thickness 0.15)) (justify left bottom) hide)
    )
    (property "Datasheet" "" (at 220.98 111.76 0)
      (effects (font (size 1.27 1.27) (thickness 0.15)) (justify left bottom) hide)
    )
    (property "Author" "Antmicro" (at 220.98 106.68 0)
      (effects (font (size 1.27 1.27) (thickness 0.15)) (justify left bottom) hide)
    )
    (property "License" "Apache-2.0" (at 220.98 109.22 0)
      (effects (font (size 1.27 1.27) (thickness 0.15)) (justify left bottom) hide)
    )
    (pin "1")
    (instances
      (project "d1600e-psu-breakout-board"
        (path ""
          (reference "#PWR019") (unit 1)
        )
      )
    )
  )

  (symbol (lib_id "antmicropower:GNDD") (at 81.28 97.79 0) (mirror y) (unit 1)
    (in_bom yes) (on_board yes) (dnp no) (fields_autoplaced)
    (property "Reference" "#PWR0116" (at 81.28 104.14 0)
      (effects (font (size 1.27 1.27)) hide)
    )
    (property "Value" "GNDD" (at 81.28 101.6 0)
      (effects (font (size 1.27 1.27) (thickness 0.15)))
    )
    (property "Footprint" "" (at 66.04 107.95 0)
      (effects (font (size 1.27 1.27) (thickness 0.15)) (justify left bottom) hide)
    )
    (property "Datasheet" "" (at 66.04 110.49 0)
      (effects (font (size 1.27 1.27) (thickness 0.15)) (justify left bottom) hide)
    )
    (property "Author" "Antmicro" (at 66.04 105.41 0)
      (effects (font (size 1.27 1.27) (thickness 0.15)) (justify left bottom) hide)
    )
    (property "License" "Apache-2.0" (at 66.04 107.95 0)
      (effects (font (size 1.27 1.27) (thickness 0.15)) (justify left bottom) hide)
    )
    (pin "1")
    (instances
      (project "d1600e-psu-breakout-board"
        (path ""
          (reference "#PWR0116") (unit 1)
        )
      )
    )
  )

  (symbol (lib_name "R_4k7_0402_2") (lib_id "antmicroResistors0402:R_4k7_0402") (at 180.34 68.58 90) (unit 1)
    (in_bom yes) (on_board yes) (dnp no)
    (property "Reference" "R5" (at 181.61 64.77 90)
      (effects (font (size 1.27 1.27)) (justify right))
    )
    (property "Value" "R_4k7_0402" (at 193.04 48.26 0)
      (effects (font (size 1.27 1.27) (thickness 0.15)) (justify left bottom) hide)
    )
    (property "Footprint" "antmicro-footprints:R_0402_1005Metric" (at 195.58 48.26 0)
      (effects (font (size 1.27 1.27) (thickness 0.15)) (justify left bottom) hide)
    )
    (property "Datasheet" "https://www.bourns.com/docs/product-datasheets/cr.pdf" (at 198.12 48.26 0)
      (effects (font (size 1.27 1.27) (thickness 0.15)) (justify left bottom) hide)
    )
    (property "Manufacturer" "Bourns" (at 203.2 48.26 0)
      (effects (font (size 1.27 1.27) (thickness 0.15)) (justify left bottom) hide)
    )
    (property "MPN" "CR0402-FX-4701GLF" (at 200.66 48.26 0)
      (effects (font (size 1.27 1.27) (thickness 0.15)) (justify left bottom) hide)
    )
    (property "Val" "4k7" (at 181.61 67.31 90)
      (effects (font (size 1.27 1.27) (thickness 0.15)) (justify right))
    )
    (property "License" "Apache-2.0" (at 205.74 48.26 0)
      (effects (font (size 1.27 1.27) (thickness 0.15)) (justify left bottom) hide)
    )
    (property "Author" "Antmicro" (at 208.28 48.26 0)
      (effects (font (size 1.27 1.27) (thickness 0.15)) (justify left bottom) hide)
    )
    (property "Tolerance" "1%" (at 190.5 48.26 0)
      (effects (font (size 1.27 1.27)) (justify left bottom) hide)
    )
    (pin "1")
    (pin "2")
    (instances
      (project "d1600e-psu-breakout-board"
        (path ""
          (reference "R5") (unit 1)
        )
      )
    )
  )

  (symbol (lib_id "antmicroOptoisolatorsLogicOutput:ACPL-217-500E") (at 157.48 110.49 0) (unit 1)
    (in_bom yes) (on_board yes) (dnp no)
    (property "Reference" "U7" (at 163.83 105.41 0)
      (effects (font (size 1.27 1.27) (thickness 0.15)))
    )
    (property "Value" "ACPL-217-500E" (at 185.42 118.11 0)
      (effects (font (size 1.27 1.27) (thickness 0.15)) (justify left bottom) hide)
    )
    (property "Footprint" "antmicro-footprints:SOIC-4_4.55x2.6mm_P1.27mm" (at 185.42 120.65 0)
      (effects (font (size 1.27 1.27) (thickness 0.15)) (justify left bottom) hide)
    )
    (property "Datasheet" "https://docs.broadcom.com/doc/AV02-0470EN" (at 185.42 123.19 0)
      (effects (font (size 1.27 1.27) (thickness 0.15)) (justify left bottom) hide)
    )
    (property "Description" "Broadcom ACPL-217-500E DC Input Transistor Output Optocoupler, Surface Mount, 4-Pin SO" (at 185.42 125.73 0)
      (effects (font (size 1.27 1.27) (thickness 0.15)) (justify left bottom) hide)
    )
    (property "Manufacturer" "Broadcom" (at 185.42 128.27 0)
      (effects (font (size 1.27 1.27) (thickness 0.15)) (justify left bottom) hide)
    )
    (property "MPN" "ACPL-217-500E" (at 163.83 107.95 0)
      (effects (font (size 1.27 1.27) (thickness 0.15)))
    )
    (property "Author" "Antmicro" (at 185.42 133.35 0)
      (effects (font (size 1.27 1.27) (thickness 0.15)) (justify left bottom) hide)
    )
    (property "License" "Apache-2.0" (at 185.42 135.89 0)
      (effects (font (size 1.27 1.27) (thickness 0.15)) (justify left bottom) hide)
    )
    (pin "1")
    (pin "2")
    (pin "3")
    (pin "4")
    (instances
      (project "d1600e-psu-breakout-board"
        (path ""
          (reference "U7") (unit 1)
        )
      )
    )
  )

  (symbol (lib_name "C_4u7_0402_4") (lib_id "antmicroCapacitors0402:C_4u7_0402") (at 295.91 158.75 90) (unit 1)
    (in_bom yes) (on_board yes) (dnp no)
    (property "Reference" "C19" (at 296.545 154.305 90)
      (effects (font (size 1.27 1.27)) (justify right))
    )
    (property "Value" "C_4u7_0402" (at 306.07 138.43 0)
      (effects (font (size 1.27 1.27) (thickness 0.15)) (justify left bottom) hide)
    )
    (property "Footprint" "antmicro-footprints:C_0402_1005Metric" (at 308.61 138.43 0)
      (effects (font (size 1.27 1.27) (thickness 0.15)) (justify left bottom) hide)
    )
    (property "Datasheet" "https://www.murata.com/products/productdetail?partno=GRM155R61A475MEAA%23" (at 311.15 138.43 0)
      (effects (font (size 1.27 1.27) (thickness 0.15)) (justify left bottom) hide)
    )
    (property "Manufacturer" "Murata" (at 316.23 138.43 0)
      (effects (font (size 1.27 1.27) (thickness 0.15)) (justify left bottom) hide)
    )
    (property "MPN" "GRM155R61A475MEAAD" (at 313.69 138.43 0)
      (effects (font (size 1.27 1.27) (thickness 0.15)) (justify left bottom) hide)
    )
    (property "Val" "4u7" (at 296.545 158.115 90)
      (effects (font (size 1.27 1.27) (thickness 0.15)) (justify right))
    )
    (property "License" "Apache-2.0" (at 318.77 138.43 0)
      (effects (font (size 1.27 1.27) (thickness 0.15)) (justify left bottom) hide)
    )
    (property "Author" "Antmicro" (at 321.31 138.43 0)
      (effects (font (size 1.27 1.27) (thickness 0.15)) (justify left bottom) hide)
    )
    (property "Voltage" "" (at 323.85 138.43 0)
      (effects (font (size 1.27 1.27)) (justify left bottom) hide)
    )
    (property "Dielectric" "" (at 326.39 138.43 0)
      (effects (font (size 1.27 1.27)) (justify left bottom) hide)
    )
    (pin "1")
    (pin "2")
    (instances
      (project "d1600e-psu-breakout-board"
        (path ""
          (reference "C19") (unit 1)
        )
      )
    )
  )

  (symbol (lib_name "R_4k7_0402_3") (lib_id "antmicroResistors0402:R_4k7_0402") (at 133.35 238.76 90) (unit 1)
    (in_bom yes) (on_board yes) (dnp no)
    (property "Reference" "R36" (at 134.62 234.95 90)
      (effects (font (size 1.27 1.27)) (justify right))
    )
    (property "Value" "R_4k7_0402" (at 146.05 218.44 0)
      (effects (font (size 1.27 1.27) (thickness 0.15)) (justify left bottom) hide)
    )
    (property "Footprint" "antmicro-footprints:R_0402_1005Metric" (at 148.59 218.44 0)
      (effects (font (size 1.27 1.27) (thickness 0.15)) (justify left bottom) hide)
    )
    (property "Datasheet" "https://www.bourns.com/docs/product-datasheets/cr.pdf" (at 151.13 218.44 0)
      (effects (font (size 1.27 1.27) (thickness 0.15)) (justify left bottom) hide)
    )
    (property "Manufacturer" "Bourns" (at 156.21 218.44 0)
      (effects (font (size 1.27 1.27) (thickness 0.15)) (justify left bottom) hide)
    )
    (property "MPN" "CR0402-FX-4701GLF" (at 153.67 218.44 0)
      (effects (font (size 1.27 1.27) (thickness 0.15)) (justify left bottom) hide)
    )
    (property "Val" "4k7" (at 134.62 237.49 90)
      (effects (font (size 1.27 1.27) (thickness 0.15)) (justify right))
    )
    (property "License" "Apache-2.0" (at 158.75 218.44 0)
      (effects (font (size 1.27 1.27) (thickness 0.15)) (justify left bottom) hide)
    )
    (property "Author" "Antmicro" (at 161.29 218.44 0)
      (effects (font (size 1.27 1.27) (thickness 0.15)) (justify left bottom) hide)
    )
    (property "Tolerance" "1%" (at 143.51 218.44 0)
      (effects (font (size 1.27 1.27)) (justify left bottom) hide)
    )
    (pin "1")
    (pin "2")
    (instances
      (project "d1600e-psu-breakout-board"
        (path ""
          (reference "R36") (unit 1)
        )
      )
    )
  )

  (symbol (lib_id "antmicroCapacitors0402:C_4u7_0402") (at 335.28 158.75 90) (unit 1)
    (in_bom yes) (on_board yes) (dnp no)
    (property "Reference" "C20" (at 335.915 154.305 90)
      (effects (font (size 1.27 1.27)) (justify right))
    )
    (property "Value" "C_4u7_0402" (at 345.44 138.43 0)
      (effects (font (size 1.27 1.27) (thickness 0.15)) (justify left bottom) hide)
    )
    (property "Footprint" "antmicro-footprints:C_0402_1005Metric" (at 347.98 138.43 0)
      (effects (font (size 1.27 1.27) (thickness 0.15)) (justify left bottom) hide)
    )
    (property "Datasheet" "https://www.murata.com/products/productdetail?partno=GRM155R61A475MEAA%23" (at 350.52 138.43 0)
      (effects (font (size 1.27 1.27) (thickness 0.15)) (justify left bottom) hide)
    )
    (property "Manufacturer" "Murata" (at 355.6 138.43 0)
      (effects (font (size 1.27 1.27) (thickness 0.15)) (justify left bottom) hide)
    )
    (property "MPN" "GRM155R61A475MEAAD" (at 353.06 138.43 0)
      (effects (font (size 1.27 1.27) (thickness 0.15)) (justify left bottom) hide)
    )
    (property "Val" "4u7" (at 335.915 158.115 90)
      (effects (font (size 1.27 1.27) (thickness 0.15)) (justify right))
    )
    (property "License" "Apache-2.0" (at 358.14 138.43 0)
      (effects (font (size 1.27 1.27) (thickness 0.15)) (justify left bottom) hide)
    )
    (property "Author" "Antmicro" (at 360.68 138.43 0)
      (effects (font (size 1.27 1.27) (thickness 0.15)) (justify left bottom) hide)
    )
    (property "Voltage" "" (at 363.22 138.43 0)
      (effects (font (size 1.27 1.27)) (justify left bottom) hide)
    )
    (property "Dielectric" "" (at 365.76 138.43 0)
      (effects (font (size 1.27 1.27)) (justify left bottom) hide)
    )
    (pin "1")
    (pin "2")
    (instances
      (project "d1600e-psu-breakout-board"
        (path ""
          (reference "C20") (unit 1)
        )
      )
    )
  )

  (symbol (lib_id "antmicroInterfaceControllers:FT4232H_VQFN") (at 104.14 73.66 0) (unit 1)
    (in_bom yes) (on_board yes) (dnp no)
    (property "Reference" "U5" (at 121.92 67.31 0)
      (effects (font (size 1.27 1.27)) (justify left))
    )
    (property "Value" "FT4232H_VQFN" (at 160.02 88.9 0)
      (effects (font (size 1.27 1.27) (thickness 0.15)) (justify left bottom) hide)
    )
    (property "Footprint" "antmicro-footprints:QFN-56-1EP_8x8mm_P0.5mm" (at 160.02 81.28 0)
      (effects (font (size 1.27 1.27) (thickness 0.15)) (justify left bottom) hide)
    )
    (property "Datasheet" "https://www.ftdichip.com/Support/Documents/DataSheets/ICs/DS_FT4232H.pdf" (at 160.02 83.82 0)
      (effects (font (size 1.27 1.27) (thickness 0.15)) (justify left bottom) hide)
    )
    (property "Manufacturer" "FTDI Chip" (at 160.02 86.36 0)
      (effects (font (size 1.27 1.27) (thickness 0.15)) (justify left bottom) hide)
    )
    (property "MPN" "FT4232H-56Q-REEL" (at 114.3 69.85 0)
      (effects (font (size 1.27 1.27) (thickness 0.15)) (justify left))
    )
    (property "Author" "Antmicro" (at 160.02 91.44 0)
      (effects (font (size 1.27 1.27) (thickness 0.15)) (justify left bottom) hide)
    )
    (property "License" "Apache-2.0" (at 160.02 93.98 0)
      (effects (font (size 1.27 1.27) (thickness 0.15)) (justify left bottom) hide)
    )
    (pin "1")
    (pin "10")
    (pin "11")
    (pin "12")
    (pin "13")
    (pin "14")
    (pin "15")
    (pin "16")
    (pin "17")
    (pin "18")
    (pin "19")
    (pin "2")
    (pin "20")
    (pin "21")
    (pin "22")
    (pin "23")
    (pin "24")
    (pin "25")
    (pin "26")
    (pin "27")
    (pin "28")
    (pin "29")
    (pin "3")
    (pin "30")
    (pin "31")
    (pin "32")
    (pin "33")
    (pin "34")
    (pin "35")
    (pin "36")
    (pin "37")
    (pin "38")
    (pin "39")
    (pin "4")
    (pin "40")
    (pin "41")
    (pin "42")
    (pin "43")
    (pin "44")
    (pin "45")
    (pin "46")
    (pin "47")
    (pin "48")
    (pin "49")
    (pin "5")
    (pin "50")
    (pin "51")
    (pin "52")
    (pin "53")
    (pin "54")
    (pin "55")
    (pin "56")
    (pin "57")
    (pin "6")
    (pin "7")
    (pin "8")
    (pin "9")
    (instances
      (project "d1600e-psu-breakout-board"
        (path ""
          (reference "U5") (unit 1)
        )
      )
    )
  )

  (symbol (lib_name "PESD5V0S2BQA_1") (lib_id "antmicroTVSDiodes:PESD5V0S2BQA") (at 316.23 34.29 0) (unit 1)
    (in_bom yes) (on_board yes) (dnp no)
    (property "Reference" "D14" (at 321.31 27.94 0)
      (effects (font (size 1.27 1.27)) (justify left))
    )
    (property "Value" "PESD5V0S2BQA" (at 344.17 44.45 0)
      (effects (font (size 1.27 1.27) (thickness 0.15)) (justify left bottom) hide)
    )
    (property "Footprint" "antmicro-footprints:TPD2E009DRTR" (at 344.17 46.99 0)
      (effects (font (size 1.27 1.27) (thickness 0.15)) (justify left bottom) hide)
    )
    (property "Datasheet" "https://4donline.ihs.com/images/VipMasterIC/IC/NEXP/NEXP-S-A0003105620/NEXP-S-A0003107857-1.pdf?hkey=6D3A4C79FDBF58556ACFDE234799DDF0" (at 344.17 49.53 0)
      (effects (font (size 1.27 1.27) (thickness 0.15)) (justify left bottom) hide)
    )
    (property "MPN" "PESD5V0S2BQA" (at 317.5 30.48 0)
      (effects (font (size 1.27 1.27) (thickness 0.15)) (justify left))
    )
    (property "Manufacturer" "Nexperia" (at 344.17 41.91 0)
      (effects (font (size 1.27 1.27) (thickness 0.15)) (justify left bottom) hide)
    )
    (property "Author" "Antmicro" (at 344.17 52.07 0)
      (effects (font (size 1.27 1.27) (thickness 0.15)) (justify left bottom) hide)
    )
    (property "License" "Apache-2.0" (at 344.17 54.61 0)
      (effects (font (size 1.27 1.27) (thickness 0.15)) (justify left bottom) hide)
    )
    (pin "1")
    (pin "2")
    (pin "3")
    (instances
      (project "d1600e-psu-breakout-board"
        (path ""
          (reference "D14") (unit 1)
        )
      )
    )
  )
)
